FILE_TYPE = MACRO_DRAWING;
SET COLOR_WIRE YELLOW;
SET COLOR_PROP MONO;
SET COLOR_DOT WHITE;
SET COLOR_ARC YELLOW;
SET COLOR_BODY GREEN;
SET COLOR_NOTE MONO;
SET PROP_DISPLAY VALUE;
SET PAGE_NUMBER P59;
FORCEADD OFFPAGE..5
(-6425 500);
FORCEPROP 2 LAST $XR1 82 
J 0
(-6769 500);
DISPLAY 0.638298 (-6769 500);
PAINT MONO (-6769 500);
FORCEPROP 2 LAST $XR0 81 
J 0
(-6679 500);
DISPLAY 0.638298 (-6679 500);
PAINT MONO (-6679 500);
FORCEPROP 2 LAST CDS_LIB mstr_standard
J 0
(-6425 500);
PAINT MONO (-6425 500);
DISPLAY INVISIBLE (-6425 500);
FORCEPROP 1 LAST OFFPAGE TRUE
J 0
(-6100 375);
DISPLAY 1.170213 (-6100 375);
PAINT GREEN (-6100 375);
DISPLAY INVISIBLE (-6100 375);
FORCEPROP 1 LAST COMMENT_BODY TRUE
J 0
(-6325 425);
DISPLAY 1.170213 (-6325 425);
PAINT GREEN (-6325 425);
DISPLAY INVISIBLE (-6325 425);
FORCEPROP 2 LAST PATH I1
J 0
(-6375 575);
DISPLAY 1.021277 (-6375 575);
PAINT ORANGE (-6375 575);
DISPLAY INVISIBLE (-6375 575);
FORCEADD TAP..6
(-5575 800);
FORCEPROP 3 LASTPIN (-5525 800) SIG_NAME M_J_CLK_DP<0>
J 0
(-5515 810);
DISPLAY 0.659574 (-5515 810);
PAINT MONO (-5515 810);
DISPLAY INVISIBLE (-5515 810);
FORCEPROP 1 LASTPIN (-5525 800) BN 0
J 0
(-5577 808);
DISPLAY 0.617021 (-5577 808);
PAINT GREEN (-5577 808);
FORCEPROP 2 LAST CDS_LIB mstr_standard
J 0
(-5575 800);
PAINT MONO (-5575 800);
DISPLAY INVISIBLE (-5575 800);
FORCEPROP 1 LAST BODY_TYPE PLUMBING
J 0
(-5575 750);
DISPLAY 1.595745 (-5575 750);
PAINT GREEN (-5575 750);
DISPLAY INVISIBLE (-5575 750);
FORCEPROP 1 LAST HDL_TAP TRUE
J 0
(-5250 675);
DISPLAY 1.595745 (-5250 675);
PAINT GREEN (-5250 675);
DISPLAY INVISIBLE (-5250 675);
FORCEPROP 1 LAST PATH I10
J 0
(-5577 800);
DISPLAY 0.872340 (-5577 800);
PAINT GREEN (-5577 800);
DISPLAY INVISIBLE (-5577 800);
FORCEADD TAP..6
R 2
(-2850 1550);
FORCEPROP 3 LASTPIN (-2900 1550) SIG_NAME M_J_ODT<3>
J 0
(-2890 1560);
DISPLAY 0.659574 (-2890 1560);
PAINT MONO (-2890 1560);
DISPLAY INVISIBLE (-2890 1560);
FORCEPROP 1 LASTPIN (-2900 1550) BN 3
J 2
(-2848 1558);
DISPLAY 0.617021 (-2848 1558);
PAINT GREEN (-2848 1558);
FORCEPROP 2 LAST CDS_LIB mstr_standard
J 0
(-2850 1550);
PAINT MONO (-2850 1550);
DISPLAY INVISIBLE (-2850 1550);
FORCEPROP 1 LAST BODY_TYPE PLUMBING
J 2
(-2850 1500);
DISPLAY 1.595745 (-2850 1500);
PAINT GREEN (-2850 1500);
DISPLAY INVISIBLE (-2850 1500);
FORCEPROP 1 LAST HDL_TAP TRUE
J 2
(-3175 1425);
DISPLAY 1.595745 (-3175 1425);
PAINT GREEN (-3175 1425);
DISPLAY INVISIBLE (-3175 1425);
FORCEPROP 1 LAST PATH I100
J 2
(-2848 1550);
DISPLAY 0.872340 (-2848 1550);
PAINT GREEN (-2848 1550);
DISPLAY INVISIBLE (-2848 1550);
FORCEADD TAP..6
R 2
(-2850 1500);
FORCEPROP 3 LASTPIN (-2900 1500) SIG_NAME M_J_ODT<2>
J 0
(-2890 1510);
DISPLAY 0.659574 (-2890 1510);
PAINT MONO (-2890 1510);
DISPLAY INVISIBLE (-2890 1510);
FORCEPROP 1 LASTPIN (-2900 1500) BN 2
J 2
(-2848 1508);
DISPLAY 0.617021 (-2848 1508);
PAINT GREEN (-2848 1508);
FORCEPROP 2 LAST CDS_LIB mstr_standard
J 0
(-2850 1500);
PAINT MONO (-2850 1500);
DISPLAY INVISIBLE (-2850 1500);
FORCEPROP 1 LAST BODY_TYPE PLUMBING
J 2
(-2850 1450);
DISPLAY 1.595745 (-2850 1450);
PAINT GREEN (-2850 1450);
DISPLAY INVISIBLE (-2850 1450);
FORCEPROP 1 LAST HDL_TAP TRUE
J 2
(-3175 1375);
DISPLAY 1.595745 (-3175 1375);
PAINT GREEN (-3175 1375);
DISPLAY INVISIBLE (-3175 1375);
FORCEPROP 1 LAST PATH I101
J 2
(-2848 1500);
DISPLAY 0.872340 (-2848 1500);
PAINT GREEN (-2848 1500);
DISPLAY INVISIBLE (-2848 1500);
FORCEADD TAP..6
R 2
(-2850 1450);
FORCEPROP 3 LASTPIN (-2900 1450) SIG_NAME M_J_ODT<1>
J 0
(-2890 1460);
DISPLAY 0.659574 (-2890 1460);
PAINT MONO (-2890 1460);
DISPLAY INVISIBLE (-2890 1460);
FORCEPROP 1 LASTPIN (-2900 1450) BN 1
J 2
(-2848 1458);
DISPLAY 0.617021 (-2848 1458);
PAINT GREEN (-2848 1458);
FORCEPROP 2 LAST CDS_LIB mstr_standard
J 0
(-2850 1450);
PAINT MONO (-2850 1450);
DISPLAY INVISIBLE (-2850 1450);
FORCEPROP 1 LAST BODY_TYPE PLUMBING
J 2
(-2850 1400);
DISPLAY 1.595745 (-2850 1400);
PAINT GREEN (-2850 1400);
DISPLAY INVISIBLE (-2850 1400);
FORCEPROP 1 LAST HDL_TAP TRUE
J 2
(-3175 1325);
DISPLAY 1.595745 (-3175 1325);
PAINT GREEN (-3175 1325);
DISPLAY INVISIBLE (-3175 1325);
FORCEPROP 1 LAST PATH I102
J 2
(-2848 1450);
DISPLAY 0.872340 (-2848 1450);
PAINT GREEN (-2848 1450);
DISPLAY INVISIBLE (-2848 1450);
FORCEADD TAP..6
R 2
(-2850 1650);
FORCEPROP 3 LASTPIN (-2900 1650) SIG_NAME M_J_CKE <0>
J 0
(-2890 1660);
DISPLAY 0.659574 (-2890 1660);
PAINT MONO (-2890 1660);
DISPLAY INVISIBLE (-2890 1660);
FORCEPROP 1 LASTPIN (-2900 1650) BN 0
J 2
(-2848 1658);
DISPLAY 0.617021 (-2848 1658);
PAINT GREEN (-2848 1658);
FORCEPROP 2 LAST CDS_LIB mstr_standard
J 0
(-2850 1650);
PAINT MONO (-2850 1650);
DISPLAY INVISIBLE (-2850 1650);
FORCEPROP 1 LAST BODY_TYPE PLUMBING
J 2
(-2850 1600);
DISPLAY 1.595745 (-2850 1600);
PAINT GREEN (-2850 1600);
DISPLAY INVISIBLE (-2850 1600);
FORCEPROP 1 LAST HDL_TAP TRUE
J 2
(-3175 1525);
DISPLAY 1.595745 (-3175 1525);
PAINT GREEN (-3175 1525);
DISPLAY INVISIBLE (-3175 1525);
FORCEPROP 1 LAST PATH I103
J 2
(-2848 1650);
DISPLAY 0.872340 (-2848 1650);
PAINT GREEN (-2848 1650);
DISPLAY INVISIBLE (-2848 1650);
FORCEADD TAP..6
R 2
(-2850 1700);
FORCEPROP 3 LASTPIN (-2900 1700) SIG_NAME M_J_CKE <1>
J 0
(-2890 1710);
DISPLAY 0.659574 (-2890 1710);
PAINT MONO (-2890 1710);
DISPLAY INVISIBLE (-2890 1710);
FORCEPROP 1 LASTPIN (-2900 1700) BN 1
J 2
(-2848 1708);
DISPLAY 0.617021 (-2848 1708);
PAINT GREEN (-2848 1708);
FORCEPROP 2 LAST CDS_LIB mstr_standard
J 0
(-2850 1700);
PAINT MONO (-2850 1700);
DISPLAY INVISIBLE (-2850 1700);
FORCEPROP 1 LAST BODY_TYPE PLUMBING
J 2
(-2850 1650);
DISPLAY 1.595745 (-2850 1650);
PAINT GREEN (-2850 1650);
DISPLAY INVISIBLE (-2850 1650);
FORCEPROP 1 LAST HDL_TAP TRUE
J 2
(-3175 1575);
DISPLAY 1.595745 (-3175 1575);
PAINT GREEN (-3175 1575);
DISPLAY INVISIBLE (-3175 1575);
FORCEPROP 1 LAST PATH I104
J 2
(-2848 1700);
DISPLAY 0.872340 (-2848 1700);
PAINT GREEN (-2848 1700);
DISPLAY INVISIBLE (-2848 1700);
FORCEADD TAP..6
R 2
(-2850 1750);
FORCEPROP 3 LASTPIN (-2900 1750) SIG_NAME M_J_CKE <2>
J 0
(-2890 1760);
DISPLAY 0.659574 (-2890 1760);
PAINT MONO (-2890 1760);
DISPLAY INVISIBLE (-2890 1760);
FORCEPROP 1 LASTPIN (-2900 1750) BN 2
J 2
(-2848 1758);
DISPLAY 0.617021 (-2848 1758);
PAINT GREEN (-2848 1758);
FORCEPROP 2 LAST CDS_LIB mstr_standard
J 0
(-2850 1750);
PAINT MONO (-2850 1750);
DISPLAY INVISIBLE (-2850 1750);
FORCEPROP 1 LAST BODY_TYPE PLUMBING
J 2
(-2850 1700);
DISPLAY 1.595745 (-2850 1700);
PAINT GREEN (-2850 1700);
DISPLAY INVISIBLE (-2850 1700);
FORCEPROP 1 LAST HDL_TAP TRUE
J 2
(-3175 1625);
DISPLAY 1.595745 (-3175 1625);
PAINT GREEN (-3175 1625);
DISPLAY INVISIBLE (-3175 1625);
FORCEPROP 1 LAST PATH I105
J 2
(-2848 1750);
DISPLAY 0.872340 (-2848 1750);
PAINT GREEN (-2848 1750);
DISPLAY INVISIBLE (-2848 1750);
FORCEADD TAP..6
R 2
(-2850 1800);
FORCEPROP 3 LASTPIN (-2900 1800) SIG_NAME M_J_CKE <3>
J 0
(-2890 1810);
DISPLAY 0.659574 (-2890 1810);
PAINT MONO (-2890 1810);
DISPLAY INVISIBLE (-2890 1810);
FORCEPROP 1 LASTPIN (-2900 1800) BN 3
J 2
(-2848 1808);
DISPLAY 0.617021 (-2848 1808);
PAINT GREEN (-2848 1808);
FORCEPROP 2 LAST CDS_LIB mstr_standard
J 0
(-2850 1800);
PAINT MONO (-2850 1800);
DISPLAY INVISIBLE (-2850 1800);
FORCEPROP 1 LAST BODY_TYPE PLUMBING
J 2
(-2850 1750);
DISPLAY 1.595745 (-2850 1750);
PAINT GREEN (-2850 1750);
DISPLAY INVISIBLE (-2850 1750);
FORCEPROP 1 LAST HDL_TAP TRUE
J 2
(-3175 1675);
DISPLAY 1.595745 (-3175 1675);
PAINT GREEN (-3175 1675);
DISPLAY INVISIBLE (-3175 1675);
FORCEPROP 1 LAST PATH I106
J 2
(-2848 1800);
DISPLAY 0.872340 (-2848 1800);
PAINT GREEN (-2848 1800);
DISPLAY INVISIBLE (-2848 1800);
FORCEADD TAP..6
R 2
(-2850 1900);
FORCEPROP 3 LASTPIN (-2900 1900) SIG_NAME M_J_MA<0>
J 0
(-2890 1910);
DISPLAY 0.659574 (-2890 1910);
PAINT MONO (-2890 1910);
DISPLAY INVISIBLE (-2890 1910);
FORCEPROP 1 LASTPIN (-2900 1900) BN 0
J 2
(-2848 1908);
DISPLAY 0.617021 (-2848 1908);
PAINT GREEN (-2848 1908);
FORCEPROP 2 LAST CDS_LIB mstr_standard
J 0
(-2850 1900);
PAINT MONO (-2850 1900);
DISPLAY INVISIBLE (-2850 1900);
FORCEPROP 1 LAST BODY_TYPE PLUMBING
J 2
(-2850 1850);
DISPLAY 1.595745 (-2850 1850);
PAINT GREEN (-2850 1850);
DISPLAY INVISIBLE (-2850 1850);
FORCEPROP 1 LAST HDL_TAP TRUE
J 2
(-3175 1775);
DISPLAY 1.595745 (-3175 1775);
PAINT GREEN (-3175 1775);
DISPLAY INVISIBLE (-3175 1775);
FORCEPROP 1 LAST PATH I107
J 2
(-2848 1900);
DISPLAY 0.872340 (-2848 1900);
PAINT GREEN (-2848 1900);
DISPLAY INVISIBLE (-2848 1900);
FORCEADD TAP..6
R 2
(-2850 1950);
FORCEPROP 3 LASTPIN (-2900 1950) SIG_NAME M_J_MA<1>
J 0
(-2890 1960);
DISPLAY 0.659574 (-2890 1960);
PAINT MONO (-2890 1960);
DISPLAY INVISIBLE (-2890 1960);
FORCEPROP 1 LASTPIN (-2900 1950) BN 1
J 2
(-2848 1958);
DISPLAY 0.617021 (-2848 1958);
PAINT GREEN (-2848 1958);
FORCEPROP 2 LAST CDS_LIB mstr_standard
J 0
(-2850 1950);
PAINT MONO (-2850 1950);
DISPLAY INVISIBLE (-2850 1950);
FORCEPROP 1 LAST BODY_TYPE PLUMBING
J 2
(-2850 1900);
DISPLAY 1.595745 (-2850 1900);
PAINT GREEN (-2850 1900);
DISPLAY INVISIBLE (-2850 1900);
FORCEPROP 1 LAST HDL_TAP TRUE
J 2
(-3175 1825);
DISPLAY 1.595745 (-3175 1825);
PAINT GREEN (-3175 1825);
DISPLAY INVISIBLE (-3175 1825);
FORCEPROP 1 LAST PATH I108
J 2
(-2848 1950);
DISPLAY 0.872340 (-2848 1950);
PAINT GREEN (-2848 1950);
DISPLAY INVISIBLE (-2848 1950);
FORCEADD TAP..6
R 2
(-2850 2050);
FORCEPROP 3 LASTPIN (-2900 2050) SIG_NAME M_J_MA<3>
J 0
(-2890 2060);
DISPLAY 0.659574 (-2890 2060);
PAINT MONO (-2890 2060);
DISPLAY INVISIBLE (-2890 2060);
FORCEPROP 1 LASTPIN (-2900 2050) BN 3
J 2
(-2848 2058);
DISPLAY 0.617021 (-2848 2058);
PAINT GREEN (-2848 2058);
FORCEPROP 2 LAST CDS_LIB mstr_standard
J 0
(-2850 2050);
PAINT MONO (-2850 2050);
DISPLAY INVISIBLE (-2850 2050);
FORCEPROP 1 LAST BODY_TYPE PLUMBING
J 2
(-2850 2000);
DISPLAY 1.595745 (-2850 2000);
PAINT GREEN (-2850 2000);
DISPLAY INVISIBLE (-2850 2000);
FORCEPROP 1 LAST HDL_TAP TRUE
J 2
(-3175 1925);
DISPLAY 1.595745 (-3175 1925);
PAINT GREEN (-3175 1925);
DISPLAY INVISIBLE (-3175 1925);
FORCEPROP 1 LAST PATH I109
J 2
(-2848 2050);
DISPLAY 0.872340 (-2848 2050);
PAINT GREEN (-2848 2050);
DISPLAY INVISIBLE (-2848 2050);
FORCEADD TAP..6
(-5575 900);
FORCEPROP 3 LASTPIN (-5525 900) SIG_NAME M_J_CLK_DP<2>
J 0
(-5515 910);
DISPLAY 0.659574 (-5515 910);
PAINT MONO (-5515 910);
DISPLAY INVISIBLE (-5515 910);
FORCEPROP 1 LASTPIN (-5525 900) BN 2
J 0
(-5577 908);
DISPLAY 0.617021 (-5577 908);
PAINT GREEN (-5577 908);
FORCEPROP 2 LAST CDS_LIB mstr_standard
J 0
(-5575 900);
PAINT MONO (-5575 900);
DISPLAY INVISIBLE (-5575 900);
FORCEPROP 1 LAST BODY_TYPE PLUMBING
J 0
(-5575 850);
DISPLAY 1.595745 (-5575 850);
PAINT GREEN (-5575 850);
DISPLAY INVISIBLE (-5575 850);
FORCEPROP 1 LAST HDL_TAP TRUE
J 0
(-5250 775);
DISPLAY 1.595745 (-5250 775);
PAINT GREEN (-5250 775);
DISPLAY INVISIBLE (-5250 775);
FORCEPROP 1 LAST PATH I11
J 0
(-5577 900);
DISPLAY 0.872340 (-5577 900);
PAINT GREEN (-5577 900);
DISPLAY INVISIBLE (-5577 900);
FORCEADD TAP..6
R 2
(-2850 2000);
FORCEPROP 3 LASTPIN (-2900 2000) SIG_NAME M_J_MA<2>
J 0
(-2890 2010);
DISPLAY 0.659574 (-2890 2010);
PAINT MONO (-2890 2010);
DISPLAY INVISIBLE (-2890 2010);
FORCEPROP 1 LASTPIN (-2900 2000) BN 2
J 2
(-2848 2008);
DISPLAY 0.617021 (-2848 2008);
PAINT GREEN (-2848 2008);
FORCEPROP 2 LAST CDS_LIB mstr_standard
J 0
(-2850 2000);
PAINT MONO (-2850 2000);
DISPLAY INVISIBLE (-2850 2000);
FORCEPROP 1 LAST BODY_TYPE PLUMBING
J 2
(-2850 1950);
DISPLAY 1.595745 (-2850 1950);
PAINT GREEN (-2850 1950);
DISPLAY INVISIBLE (-2850 1950);
FORCEPROP 1 LAST HDL_TAP TRUE
J 2
(-3175 1875);
DISPLAY 1.595745 (-3175 1875);
PAINT GREEN (-3175 1875);
DISPLAY INVISIBLE (-3175 1875);
FORCEPROP 1 LAST PATH I110
J 2
(-2848 2000);
DISPLAY 0.872340 (-2848 2000);
PAINT GREEN (-2848 2000);
DISPLAY INVISIBLE (-2848 2000);
FORCEADD TAP..6
R 2
(-2850 2100);
FORCEPROP 3 LASTPIN (-2900 2100) SIG_NAME M_J_MA<4>
J 0
(-2890 2110);
DISPLAY 0.659574 (-2890 2110);
PAINT MONO (-2890 2110);
DISPLAY INVISIBLE (-2890 2110);
FORCEPROP 1 LASTPIN (-2900 2100) BN 4
J 2
(-2848 2108);
DISPLAY 0.617021 (-2848 2108);
PAINT GREEN (-2848 2108);
FORCEPROP 2 LAST CDS_LIB mstr_standard
J 0
(-2850 2100);
PAINT MONO (-2850 2100);
DISPLAY INVISIBLE (-2850 2100);
FORCEPROP 1 LAST BODY_TYPE PLUMBING
J 2
(-2850 2050);
DISPLAY 1.595745 (-2850 2050);
PAINT GREEN (-2850 2050);
DISPLAY INVISIBLE (-2850 2050);
FORCEPROP 1 LAST HDL_TAP TRUE
J 2
(-3175 1975);
DISPLAY 1.595745 (-3175 1975);
PAINT GREEN (-3175 1975);
DISPLAY INVISIBLE (-3175 1975);
FORCEPROP 1 LAST PATH I111
J 2
(-2848 2100);
DISPLAY 0.872340 (-2848 2100);
PAINT GREEN (-2848 2100);
DISPLAY INVISIBLE (-2848 2100);
FORCEADD TAP..6
R 2
(-2850 2150);
FORCEPROP 3 LASTPIN (-2900 2150) SIG_NAME M_J_MA<5>
J 0
(-2890 2160);
DISPLAY 0.659574 (-2890 2160);
PAINT MONO (-2890 2160);
DISPLAY INVISIBLE (-2890 2160);
FORCEPROP 1 LASTPIN (-2900 2150) BN 5
J 2
(-2848 2158);
DISPLAY 0.617021 (-2848 2158);
PAINT GREEN (-2848 2158);
FORCEPROP 2 LAST CDS_LIB mstr_standard
J 0
(-2850 2150);
PAINT MONO (-2850 2150);
DISPLAY INVISIBLE (-2850 2150);
FORCEPROP 1 LAST BODY_TYPE PLUMBING
J 2
(-2850 2100);
DISPLAY 1.595745 (-2850 2100);
PAINT GREEN (-2850 2100);
DISPLAY INVISIBLE (-2850 2100);
FORCEPROP 1 LAST HDL_TAP TRUE
J 2
(-3175 2025);
DISPLAY 1.595745 (-3175 2025);
PAINT GREEN (-3175 2025);
DISPLAY INVISIBLE (-3175 2025);
FORCEPROP 1 LAST PATH I112
J 2
(-2848 2150);
DISPLAY 0.872340 (-2848 2150);
PAINT GREEN (-2848 2150);
DISPLAY INVISIBLE (-2848 2150);
FORCEADD TAP..6
R 2
(-2850 2200);
FORCEPROP 3 LASTPIN (-2900 2200) SIG_NAME M_J_MA<6>
J 0
(-2890 2210);
DISPLAY 0.659574 (-2890 2210);
PAINT MONO (-2890 2210);
DISPLAY INVISIBLE (-2890 2210);
FORCEPROP 1 LASTPIN (-2900 2200) BN 6
J 2
(-2848 2208);
DISPLAY 0.617021 (-2848 2208);
PAINT GREEN (-2848 2208);
FORCEPROP 2 LAST CDS_LIB mstr_standard
J 0
(-2850 2200);
PAINT MONO (-2850 2200);
DISPLAY INVISIBLE (-2850 2200);
FORCEPROP 1 LAST BODY_TYPE PLUMBING
J 2
(-2850 2150);
DISPLAY 1.595745 (-2850 2150);
PAINT GREEN (-2850 2150);
DISPLAY INVISIBLE (-2850 2150);
FORCEPROP 1 LAST HDL_TAP TRUE
J 2
(-3175 2075);
DISPLAY 1.595745 (-3175 2075);
PAINT GREEN (-3175 2075);
DISPLAY INVISIBLE (-3175 2075);
FORCEPROP 1 LAST PATH I113
J 2
(-2848 2200);
DISPLAY 0.872340 (-2848 2200);
PAINT GREEN (-2848 2200);
DISPLAY INVISIBLE (-2848 2200);
FORCEADD TAP..6
R 2
(-2850 2300);
FORCEPROP 3 LASTPIN (-2900 2300) SIG_NAME M_J_MA<8>
J 0
(-2890 2310);
DISPLAY 0.659574 (-2890 2310);
PAINT MONO (-2890 2310);
DISPLAY INVISIBLE (-2890 2310);
FORCEPROP 1 LASTPIN (-2900 2300) BN 8
J 2
(-2848 2308);
DISPLAY 0.617021 (-2848 2308);
PAINT GREEN (-2848 2308);
FORCEPROP 2 LAST CDS_LIB mstr_standard
J 0
(-2850 2300);
PAINT MONO (-2850 2300);
DISPLAY INVISIBLE (-2850 2300);
FORCEPROP 1 LAST BODY_TYPE PLUMBING
J 2
(-2850 2250);
DISPLAY 1.595745 (-2850 2250);
PAINT GREEN (-2850 2250);
DISPLAY INVISIBLE (-2850 2250);
FORCEPROP 1 LAST HDL_TAP TRUE
J 2
(-3175 2175);
DISPLAY 1.595745 (-3175 2175);
PAINT GREEN (-3175 2175);
DISPLAY INVISIBLE (-3175 2175);
FORCEPROP 1 LAST PATH I114
J 2
(-2848 2300);
DISPLAY 0.872340 (-2848 2300);
PAINT GREEN (-2848 2300);
DISPLAY INVISIBLE (-2848 2300);
FORCEADD TAP..6
R 2
(-2850 2250);
FORCEPROP 3 LASTPIN (-2900 2250) SIG_NAME M_J_MA<7>
J 0
(-2890 2260);
DISPLAY 0.659574 (-2890 2260);
PAINT MONO (-2890 2260);
DISPLAY INVISIBLE (-2890 2260);
FORCEPROP 1 LASTPIN (-2900 2250) BN 7
J 2
(-2848 2258);
DISPLAY 0.617021 (-2848 2258);
PAINT GREEN (-2848 2258);
FORCEPROP 2 LAST CDS_LIB mstr_standard
J 0
(-2850 2250);
PAINT MONO (-2850 2250);
DISPLAY INVISIBLE (-2850 2250);
FORCEPROP 1 LAST BODY_TYPE PLUMBING
J 2
(-2850 2200);
DISPLAY 1.595745 (-2850 2200);
PAINT GREEN (-2850 2200);
DISPLAY INVISIBLE (-2850 2200);
FORCEPROP 1 LAST HDL_TAP TRUE
J 2
(-3175 2125);
DISPLAY 1.595745 (-3175 2125);
PAINT GREEN (-3175 2125);
DISPLAY INVISIBLE (-3175 2125);
FORCEPROP 1 LAST PATH I115
J 2
(-2848 2250);
DISPLAY 0.872340 (-2848 2250);
PAINT GREEN (-2848 2250);
DISPLAY INVISIBLE (-2848 2250);
FORCEADD TAP..6
R 2
(-2850 2450);
FORCEPROP 3 LASTPIN (-2900 2450) SIG_NAME M_J_MA<11>
J 0
(-2890 2460);
DISPLAY 0.659574 (-2890 2460);
PAINT MONO (-2890 2460);
DISPLAY INVISIBLE (-2890 2460);
FORCEPROP 1 LASTPIN (-2900 2450) BN 11
J 2
(-2848 2458);
DISPLAY 0.617021 (-2848 2458);
PAINT GREEN (-2848 2458);
FORCEPROP 2 LAST CDS_LIB mstr_standard
J 0
(-2850 2450);
PAINT MONO (-2850 2450);
DISPLAY INVISIBLE (-2850 2450);
FORCEPROP 1 LAST BODY_TYPE PLUMBING
J 2
(-2850 2400);
DISPLAY 1.595745 (-2850 2400);
PAINT GREEN (-2850 2400);
DISPLAY INVISIBLE (-2850 2400);
FORCEPROP 1 LAST HDL_TAP TRUE
J 2
(-3175 2325);
DISPLAY 1.595745 (-3175 2325);
PAINT GREEN (-3175 2325);
DISPLAY INVISIBLE (-3175 2325);
FORCEPROP 1 LAST PATH I116
J 2
(-2848 2450);
DISPLAY 0.872340 (-2848 2450);
PAINT GREEN (-2848 2450);
DISPLAY INVISIBLE (-2848 2450);
FORCEADD TAP..6
R 2
(-2850 2400);
FORCEPROP 3 LASTPIN (-2900 2400) SIG_NAME M_J_MA<10>
J 0
(-2890 2410);
DISPLAY 0.659574 (-2890 2410);
PAINT MONO (-2890 2410);
DISPLAY INVISIBLE (-2890 2410);
FORCEPROP 1 LASTPIN (-2900 2400) BN 10
J 2
(-2848 2408);
DISPLAY 0.617021 (-2848 2408);
PAINT GREEN (-2848 2408);
FORCEPROP 2 LAST CDS_LIB mstr_standard
J 0
(-2850 2400);
PAINT MONO (-2850 2400);
DISPLAY INVISIBLE (-2850 2400);
FORCEPROP 1 LAST BODY_TYPE PLUMBING
J 2
(-2850 2350);
DISPLAY 1.595745 (-2850 2350);
PAINT GREEN (-2850 2350);
DISPLAY INVISIBLE (-2850 2350);
FORCEPROP 1 LAST HDL_TAP TRUE
J 2
(-3175 2275);
DISPLAY 1.595745 (-3175 2275);
PAINT GREEN (-3175 2275);
DISPLAY INVISIBLE (-3175 2275);
FORCEPROP 1 LAST PATH I117
J 2
(-2848 2400);
DISPLAY 0.872340 (-2848 2400);
PAINT GREEN (-2848 2400);
DISPLAY INVISIBLE (-2848 2400);
FORCEADD TAP..6
R 2
(-2850 2350);
FORCEPROP 3 LASTPIN (-2900 2350) SIG_NAME M_J_MA<9>
J 0
(-2890 2360);
DISPLAY 0.659574 (-2890 2360);
PAINT MONO (-2890 2360);
DISPLAY INVISIBLE (-2890 2360);
FORCEPROP 1 LASTPIN (-2900 2350) BN 9
J 2
(-2848 2358);
DISPLAY 0.617021 (-2848 2358);
PAINT GREEN (-2848 2358);
FORCEPROP 2 LAST CDS_LIB mstr_standard
J 0
(-2850 2350);
PAINT MONO (-2850 2350);
DISPLAY INVISIBLE (-2850 2350);
FORCEPROP 1 LAST BODY_TYPE PLUMBING
J 2
(-2850 2300);
DISPLAY 1.595745 (-2850 2300);
PAINT GREEN (-2850 2300);
DISPLAY INVISIBLE (-2850 2300);
FORCEPROP 1 LAST HDL_TAP TRUE
J 2
(-3175 2225);
DISPLAY 1.595745 (-3175 2225);
PAINT GREEN (-3175 2225);
DISPLAY INVISIBLE (-3175 2225);
FORCEPROP 1 LAST PATH I118
J 2
(-2848 2350);
DISPLAY 0.872340 (-2848 2350);
PAINT GREEN (-2848 2350);
DISPLAY INVISIBLE (-2848 2350);
FORCEADD TAP..6
R 2
(-2850 2500);
FORCEPROP 3 LASTPIN (-2900 2500) SIG_NAME M_J_MA<12>
J 0
(-2890 2510);
DISPLAY 0.659574 (-2890 2510);
PAINT MONO (-2890 2510);
DISPLAY INVISIBLE (-2890 2510);
FORCEPROP 1 LASTPIN (-2900 2500) BN 12
J 2
(-2848 2508);
DISPLAY 0.617021 (-2848 2508);
PAINT GREEN (-2848 2508);
FORCEPROP 2 LAST CDS_LIB mstr_standard
J 0
(-2850 2500);
PAINT MONO (-2850 2500);
DISPLAY INVISIBLE (-2850 2500);
FORCEPROP 1 LAST BODY_TYPE PLUMBING
J 2
(-2850 2450);
DISPLAY 1.595745 (-2850 2450);
PAINT GREEN (-2850 2450);
DISPLAY INVISIBLE (-2850 2450);
FORCEPROP 1 LAST HDL_TAP TRUE
J 2
(-3175 2375);
DISPLAY 1.595745 (-3175 2375);
PAINT GREEN (-3175 2375);
DISPLAY INVISIBLE (-3175 2375);
FORCEPROP 1 LAST PATH I119
J 2
(-2848 2500);
DISPLAY 0.872340 (-2848 2500);
PAINT GREEN (-2848 2500);
DISPLAY INVISIBLE (-2848 2500);
FORCEADD TAP..6
(-5575 950);
FORCEPROP 3 LASTPIN (-5525 950) SIG_NAME M_J_CLK_DP<3>
J 0
(-5515 960);
DISPLAY 0.659574 (-5515 960);
PAINT MONO (-5515 960);
DISPLAY INVISIBLE (-5515 960);
FORCEPROP 1 LASTPIN (-5525 950) BN 3
J 0
(-5577 958);
DISPLAY 0.617021 (-5577 958);
PAINT GREEN (-5577 958);
FORCEPROP 2 LAST CDS_LIB mstr_standard
J 0
(-5575 950);
PAINT MONO (-5575 950);
DISPLAY INVISIBLE (-5575 950);
FORCEPROP 1 LAST BODY_TYPE PLUMBING
J 0
(-5575 900);
DISPLAY 1.595745 (-5575 900);
PAINT GREEN (-5575 900);
DISPLAY INVISIBLE (-5575 900);
FORCEPROP 1 LAST HDL_TAP TRUE
J 0
(-5250 825);
DISPLAY 1.595745 (-5250 825);
PAINT GREEN (-5250 825);
DISPLAY INVISIBLE (-5250 825);
FORCEPROP 1 LAST PATH I12
J 0
(-5577 950);
DISPLAY 0.872340 (-5577 950);
PAINT GREEN (-5577 950);
DISPLAY INVISIBLE (-5577 950);
FORCEADD TAP..6
R 2
(-2850 2550);
FORCEPROP 3 LASTPIN (-2900 2550) SIG_NAME M_J_MA<13>
J 0
(-2890 2560);
DISPLAY 0.659574 (-2890 2560);
PAINT MONO (-2890 2560);
DISPLAY INVISIBLE (-2890 2560);
FORCEPROP 1 LASTPIN (-2900 2550) BN 13
J 2
(-2848 2558);
DISPLAY 0.617021 (-2848 2558);
PAINT GREEN (-2848 2558);
FORCEPROP 2 LAST CDS_LIB mstr_standard
J 0
(-2850 2550);
PAINT MONO (-2850 2550);
DISPLAY INVISIBLE (-2850 2550);
FORCEPROP 1 LAST BODY_TYPE PLUMBING
J 2
(-2850 2500);
DISPLAY 1.595745 (-2850 2500);
PAINT GREEN (-2850 2500);
DISPLAY INVISIBLE (-2850 2500);
FORCEPROP 1 LAST HDL_TAP TRUE
J 2
(-3175 2425);
DISPLAY 1.595745 (-3175 2425);
PAINT GREEN (-3175 2425);
DISPLAY INVISIBLE (-3175 2425);
FORCEPROP 1 LAST PATH I120
J 2
(-2848 2550);
DISPLAY 0.872340 (-2848 2550);
PAINT GREEN (-2848 2550);
DISPLAY INVISIBLE (-2848 2550);
FORCEADD TAP..6
R 2
(-2850 2600);
FORCEPROP 3 LASTPIN (-2900 2600) SIG_NAME M_J_MA<14>
J 0
(-2890 2610);
DISPLAY 0.659574 (-2890 2610);
PAINT MONO (-2890 2610);
DISPLAY INVISIBLE (-2890 2610);
FORCEPROP 1 LASTPIN (-2900 2600) BN 14
J 2
(-2848 2608);
DISPLAY 0.617021 (-2848 2608);
PAINT GREEN (-2848 2608);
FORCEPROP 2 LAST CDS_LIB mstr_standard
J 0
(-2850 2600);
PAINT MONO (-2850 2600);
DISPLAY INVISIBLE (-2850 2600);
FORCEPROP 1 LAST BODY_TYPE PLUMBING
J 2
(-2850 2550);
DISPLAY 1.595745 (-2850 2550);
PAINT GREEN (-2850 2550);
DISPLAY INVISIBLE (-2850 2550);
FORCEPROP 1 LAST HDL_TAP TRUE
J 2
(-3175 2475);
DISPLAY 1.595745 (-3175 2475);
PAINT GREEN (-3175 2475);
DISPLAY INVISIBLE (-3175 2475);
FORCEPROP 1 LAST PATH I121
J 2
(-2848 2600);
DISPLAY 0.872340 (-2848 2600);
PAINT GREEN (-2848 2600);
DISPLAY INVISIBLE (-2848 2600);
FORCEADD TAP..6
R 2
(-2850 2650);
FORCEPROP 3 LASTPIN (-2900 2650) SIG_NAME M_J_MA<15>
J 0
(-2890 2660);
DISPLAY 0.659574 (-2890 2660);
PAINT MONO (-2890 2660);
DISPLAY INVISIBLE (-2890 2660);
FORCEPROP 1 LASTPIN (-2900 2650) BN 15
J 2
(-2848 2658);
DISPLAY 0.617021 (-2848 2658);
PAINT GREEN (-2848 2658);
FORCEPROP 2 LAST CDS_LIB mstr_standard
J 0
(-2850 2650);
PAINT MONO (-2850 2650);
DISPLAY INVISIBLE (-2850 2650);
FORCEPROP 1 LAST BODY_TYPE PLUMBING
J 2
(-2850 2600);
DISPLAY 1.595745 (-2850 2600);
PAINT GREEN (-2850 2600);
DISPLAY INVISIBLE (-2850 2600);
FORCEPROP 1 LAST HDL_TAP TRUE
J 2
(-3175 2525);
DISPLAY 1.595745 (-3175 2525);
PAINT GREEN (-3175 2525);
DISPLAY INVISIBLE (-3175 2525);
FORCEPROP 1 LAST PATH I122
J 2
(-2848 2650);
DISPLAY 0.872340 (-2848 2650);
PAINT GREEN (-2848 2650);
DISPLAY INVISIBLE (-2848 2650);
FORCEADD TAP..6
R 2
(-2850 2700);
FORCEPROP 3 LASTPIN (-2900 2700) SIG_NAME M_J_MA<16>
J 0
(-2890 2710);
DISPLAY 0.659574 (-2890 2710);
PAINT MONO (-2890 2710);
DISPLAY INVISIBLE (-2890 2710);
FORCEPROP 1 LASTPIN (-2900 2700) BN 16
J 2
(-2848 2708);
DISPLAY 0.617021 (-2848 2708);
PAINT GREEN (-2848 2708);
FORCEPROP 2 LAST CDS_LIB mstr_standard
J 0
(-2850 2700);
PAINT MONO (-2850 2700);
DISPLAY INVISIBLE (-2850 2700);
FORCEPROP 1 LAST BODY_TYPE PLUMBING
J 2
(-2850 2650);
DISPLAY 1.595745 (-2850 2650);
PAINT GREEN (-2850 2650);
DISPLAY INVISIBLE (-2850 2650);
FORCEPROP 1 LAST HDL_TAP TRUE
J 2
(-3175 2575);
DISPLAY 1.595745 (-3175 2575);
PAINT GREEN (-3175 2575);
DISPLAY INVISIBLE (-3175 2575);
FORCEPROP 1 LAST PATH I123
J 2
(-2848 2700);
DISPLAY 0.872340 (-2848 2700);
PAINT GREEN (-2848 2700);
DISPLAY INVISIBLE (-2848 2700);
FORCEADD TAP..6
R 2
(-2850 2750);
FORCEPROP 3 LASTPIN (-2900 2750) SIG_NAME M_J_MA<17>
J 0
(-2890 2760);
DISPLAY 0.659574 (-2890 2760);
PAINT MONO (-2890 2760);
DISPLAY INVISIBLE (-2890 2760);
FORCEPROP 1 LASTPIN (-2900 2750) BN 17
J 2
(-2848 2758);
DISPLAY 0.617021 (-2848 2758);
PAINT GREEN (-2848 2758);
FORCEPROP 2 LAST CDS_LIB mstr_standard
J 0
(-2850 2750);
PAINT MONO (-2850 2750);
DISPLAY INVISIBLE (-2850 2750);
FORCEPROP 1 LAST BODY_TYPE PLUMBING
J 2
(-2850 2700);
DISPLAY 1.595745 (-2850 2700);
PAINT GREEN (-2850 2700);
DISPLAY INVISIBLE (-2850 2700);
FORCEPROP 1 LAST HDL_TAP TRUE
J 2
(-3175 2625);
DISPLAY 1.595745 (-3175 2625);
PAINT GREEN (-3175 2625);
DISPLAY INVISIBLE (-3175 2625);
FORCEPROP 1 LAST PATH I124
J 2
(-2848 2750);
DISPLAY 0.872340 (-2848 2750);
PAINT GREEN (-2848 2750);
DISPLAY INVISIBLE (-2848 2750);
FORCEADD TAP..6
R 2
(-2850 2900);
FORCEPROP 3 LASTPIN (-2900 2900) SIG_NAME M_J_DQS_DN<1>
J 0
(-2890 2910);
DISPLAY 0.659574 (-2890 2910);
PAINT MONO (-2890 2910);
DISPLAY INVISIBLE (-2890 2910);
FORCEPROP 1 LASTPIN (-2900 2900) BN 1
J 2
(-2848 2908);
DISPLAY 0.617021 (-2848 2908);
PAINT GREEN (-2848 2908);
FORCEPROP 2 LAST CDS_LIB mstr_standard
J 0
(-2850 2900);
PAINT MONO (-2850 2900);
DISPLAY INVISIBLE (-2850 2900);
FORCEPROP 1 LAST BODY_TYPE PLUMBING
J 2
(-2850 2850);
DISPLAY 1.595745 (-2850 2850);
PAINT GREEN (-2850 2850);
DISPLAY INVISIBLE (-2850 2850);
FORCEPROP 1 LAST HDL_TAP TRUE
J 2
(-3175 2775);
DISPLAY 1.595745 (-3175 2775);
PAINT GREEN (-3175 2775);
DISPLAY INVISIBLE (-3175 2775);
FORCEPROP 1 LAST PATH I125
J 2
(-2848 2900);
DISPLAY 0.872340 (-2848 2900);
PAINT GREEN (-2848 2900);
DISPLAY INVISIBLE (-2848 2900);
FORCEADD TAP..6
R 2
(-2850 2950);
FORCEPROP 3 LASTPIN (-2900 2950) SIG_NAME M_J_DQS_DN<2>
J 0
(-2890 2960);
DISPLAY 0.659574 (-2890 2960);
PAINT MONO (-2890 2960);
DISPLAY INVISIBLE (-2890 2960);
FORCEPROP 1 LASTPIN (-2900 2950) BN 2
J 2
(-2848 2958);
DISPLAY 0.617021 (-2848 2958);
PAINT GREEN (-2848 2958);
FORCEPROP 2 LAST CDS_LIB mstr_standard
J 0
(-2850 2950);
PAINT MONO (-2850 2950);
DISPLAY INVISIBLE (-2850 2950);
FORCEPROP 1 LAST BODY_TYPE PLUMBING
J 2
(-2850 2900);
DISPLAY 1.595745 (-2850 2900);
PAINT GREEN (-2850 2900);
DISPLAY INVISIBLE (-2850 2900);
FORCEPROP 1 LAST HDL_TAP TRUE
J 2
(-3175 2825);
DISPLAY 1.595745 (-3175 2825);
PAINT GREEN (-3175 2825);
DISPLAY INVISIBLE (-3175 2825);
FORCEPROP 1 LAST PATH I126
J 2
(-2848 2950);
DISPLAY 0.872340 (-2848 2950);
PAINT GREEN (-2848 2950);
DISPLAY INVISIBLE (-2848 2950);
FORCEADD TAP..6
R 2
(-2850 2850);
FORCEPROP 3 LASTPIN (-2900 2850) SIG_NAME M_J_DQS_DN<0>
J 0
(-2890 2860);
DISPLAY 0.659574 (-2890 2860);
PAINT MONO (-2890 2860);
DISPLAY INVISIBLE (-2890 2860);
FORCEPROP 1 LASTPIN (-2900 2850) BN 0
J 2
(-2848 2858);
DISPLAY 0.617021 (-2848 2858);
PAINT GREEN (-2848 2858);
FORCEPROP 2 LAST CDS_LIB mstr_standard
J 0
(-2850 2850);
PAINT MONO (-2850 2850);
DISPLAY INVISIBLE (-2850 2850);
FORCEPROP 1 LAST BODY_TYPE PLUMBING
J 2
(-2850 2800);
DISPLAY 1.595745 (-2850 2800);
PAINT GREEN (-2850 2800);
DISPLAY INVISIBLE (-2850 2800);
FORCEPROP 1 LAST HDL_TAP TRUE
J 2
(-3175 2725);
DISPLAY 1.595745 (-3175 2725);
PAINT GREEN (-3175 2725);
DISPLAY INVISIBLE (-3175 2725);
FORCEPROP 1 LAST PATH I127
J 2
(-2848 2850);
DISPLAY 0.872340 (-2848 2850);
PAINT GREEN (-2848 2850);
DISPLAY INVISIBLE (-2848 2850);
FORCEADD TAP..6
R 2
(-2850 3050);
FORCEPROP 3 LASTPIN (-2900 3050) SIG_NAME M_J_DQS_DN<4>
J 0
(-2890 3060);
DISPLAY 0.659574 (-2890 3060);
PAINT MONO (-2890 3060);
DISPLAY INVISIBLE (-2890 3060);
FORCEPROP 1 LASTPIN (-2900 3050) BN 4
J 2
(-2848 3058);
DISPLAY 0.617021 (-2848 3058);
PAINT GREEN (-2848 3058);
FORCEPROP 2 LAST CDS_LIB mstr_standard
J 0
(-2850 3050);
PAINT MONO (-2850 3050);
DISPLAY INVISIBLE (-2850 3050);
FORCEPROP 1 LAST BODY_TYPE PLUMBING
J 2
(-2850 3000);
DISPLAY 1.595745 (-2850 3000);
PAINT GREEN (-2850 3000);
DISPLAY INVISIBLE (-2850 3000);
FORCEPROP 1 LAST HDL_TAP TRUE
J 2
(-3175 2925);
DISPLAY 1.595745 (-3175 2925);
PAINT GREEN (-3175 2925);
DISPLAY INVISIBLE (-3175 2925);
FORCEPROP 1 LAST PATH I128
J 2
(-2848 3050);
DISPLAY 0.872340 (-2848 3050);
PAINT GREEN (-2848 3050);
DISPLAY INVISIBLE (-2848 3050);
FORCEADD TAP..6
R 2
(-2850 3000);
FORCEPROP 3 LASTPIN (-2900 3000) SIG_NAME M_J_DQS_DN<3>
J 0
(-2890 3010);
DISPLAY 0.659574 (-2890 3010);
PAINT MONO (-2890 3010);
DISPLAY INVISIBLE (-2890 3010);
FORCEPROP 1 LASTPIN (-2900 3000) BN 3
J 2
(-2848 3008);
DISPLAY 0.617021 (-2848 3008);
PAINT GREEN (-2848 3008);
FORCEPROP 2 LAST CDS_LIB mstr_standard
J 0
(-2850 3000);
PAINT MONO (-2850 3000);
DISPLAY INVISIBLE (-2850 3000);
FORCEPROP 1 LAST BODY_TYPE PLUMBING
J 2
(-2850 2950);
DISPLAY 1.595745 (-2850 2950);
PAINT GREEN (-2850 2950);
DISPLAY INVISIBLE (-2850 2950);
FORCEPROP 1 LAST HDL_TAP TRUE
J 2
(-3175 2875);
DISPLAY 1.595745 (-3175 2875);
PAINT GREEN (-3175 2875);
DISPLAY INVISIBLE (-3175 2875);
FORCEPROP 1 LAST PATH I129
J 2
(-2848 3000);
DISPLAY 0.872340 (-2848 3000);
PAINT GREEN (-2848 3000);
DISPLAY INVISIBLE (-2848 3000);
FORCEADD TAP..6
(-5575 1050);
FORCEPROP 3 LASTPIN (-5525 1050) SIG_NAME M_J_ECC<0>
J 0
(-5515 1060);
DISPLAY 0.659574 (-5515 1060);
PAINT MONO (-5515 1060);
DISPLAY INVISIBLE (-5515 1060);
FORCEPROP 1 LASTPIN (-5525 1050) BN 0
J 0
(-5577 1058);
DISPLAY 0.617021 (-5577 1058);
PAINT GREEN (-5577 1058);
FORCEPROP 2 LAST CDS_LIB mstr_standard
J 0
(-5575 1050);
PAINT MONO (-5575 1050);
DISPLAY INVISIBLE (-5575 1050);
FORCEPROP 1 LAST BODY_TYPE PLUMBING
J 0
(-5575 1000);
DISPLAY 1.595745 (-5575 1000);
PAINT GREEN (-5575 1000);
DISPLAY INVISIBLE (-5575 1000);
FORCEPROP 1 LAST HDL_TAP TRUE
J 0
(-5250 925);
DISPLAY 1.595745 (-5250 925);
PAINT GREEN (-5250 925);
DISPLAY INVISIBLE (-5250 925);
FORCEPROP 1 LAST PATH I13
J 0
(-5577 1050);
DISPLAY 0.872340 (-5577 1050);
PAINT GREEN (-5577 1050);
DISPLAY INVISIBLE (-5577 1050);
FORCEADD TAP..6
R 2
(-2850 3100);
FORCEPROP 3 LASTPIN (-2900 3100) SIG_NAME M_J_DQS_DN<5>
J 0
(-2890 3110);
DISPLAY 0.659574 (-2890 3110);
PAINT MONO (-2890 3110);
DISPLAY INVISIBLE (-2890 3110);
FORCEPROP 1 LASTPIN (-2900 3100) BN 5
J 2
(-2848 3108);
DISPLAY 0.617021 (-2848 3108);
PAINT GREEN (-2848 3108);
FORCEPROP 2 LAST CDS_LIB mstr_standard
J 0
(-2850 3100);
PAINT MONO (-2850 3100);
DISPLAY INVISIBLE (-2850 3100);
FORCEPROP 1 LAST BODY_TYPE PLUMBING
J 2
(-2850 3050);
DISPLAY 1.595745 (-2850 3050);
PAINT GREEN (-2850 3050);
DISPLAY INVISIBLE (-2850 3050);
FORCEPROP 1 LAST HDL_TAP TRUE
J 2
(-3175 2975);
DISPLAY 1.595745 (-3175 2975);
PAINT GREEN (-3175 2975);
DISPLAY INVISIBLE (-3175 2975);
FORCEPROP 1 LAST PATH I130
J 2
(-2848 3100);
DISPLAY 0.872340 (-2848 3100);
PAINT GREEN (-2848 3100);
DISPLAY INVISIBLE (-2848 3100);
FORCEADD TAP..6
R 2
(-2850 3150);
FORCEPROP 3 LASTPIN (-2900 3150) SIG_NAME M_J_DQS_DN<6>
J 0
(-2890 3160);
DISPLAY 0.659574 (-2890 3160);
PAINT MONO (-2890 3160);
DISPLAY INVISIBLE (-2890 3160);
FORCEPROP 1 LASTPIN (-2900 3150) BN 6
J 2
(-2848 3158);
DISPLAY 0.617021 (-2848 3158);
PAINT GREEN (-2848 3158);
FORCEPROP 2 LAST CDS_LIB mstr_standard
J 0
(-2850 3150);
PAINT MONO (-2850 3150);
DISPLAY INVISIBLE (-2850 3150);
FORCEPROP 1 LAST BODY_TYPE PLUMBING
J 2
(-2850 3100);
DISPLAY 1.595745 (-2850 3100);
PAINT GREEN (-2850 3100);
DISPLAY INVISIBLE (-2850 3100);
FORCEPROP 1 LAST HDL_TAP TRUE
J 2
(-3175 3025);
DISPLAY 1.595745 (-3175 3025);
PAINT GREEN (-3175 3025);
DISPLAY INVISIBLE (-3175 3025);
FORCEPROP 1 LAST PATH I131
J 2
(-2848 3150);
DISPLAY 0.872340 (-2848 3150);
PAINT GREEN (-2848 3150);
DISPLAY INVISIBLE (-2848 3150);
FORCEADD TAP..6
R 2
(-2850 3200);
FORCEPROP 3 LASTPIN (-2900 3200) SIG_NAME M_J_DQS_DN<7>
J 0
(-2890 3210);
DISPLAY 0.659574 (-2890 3210);
PAINT MONO (-2890 3210);
DISPLAY INVISIBLE (-2890 3210);
FORCEPROP 1 LASTPIN (-2900 3200) BN 7
J 2
(-2848 3208);
DISPLAY 0.617021 (-2848 3208);
PAINT GREEN (-2848 3208);
FORCEPROP 2 LAST CDS_LIB mstr_standard
J 0
(-2850 3200);
PAINT MONO (-2850 3200);
DISPLAY INVISIBLE (-2850 3200);
FORCEPROP 1 LAST BODY_TYPE PLUMBING
J 2
(-2850 3150);
DISPLAY 1.595745 (-2850 3150);
PAINT GREEN (-2850 3150);
DISPLAY INVISIBLE (-2850 3150);
FORCEPROP 1 LAST HDL_TAP TRUE
J 2
(-3175 3075);
DISPLAY 1.595745 (-3175 3075);
PAINT GREEN (-3175 3075);
DISPLAY INVISIBLE (-3175 3075);
FORCEPROP 1 LAST PATH I132
J 2
(-2848 3200);
DISPLAY 0.872340 (-2848 3200);
PAINT GREEN (-2848 3200);
DISPLAY INVISIBLE (-2848 3200);
FORCEADD TAP..6
R 2
(-2850 3250);
FORCEPROP 3 LASTPIN (-2900 3250) SIG_NAME M_J_DQS_DN<8>
J 0
(-2890 3260);
DISPLAY 0.659574 (-2890 3260);
PAINT MONO (-2890 3260);
DISPLAY INVISIBLE (-2890 3260);
FORCEPROP 1 LASTPIN (-2900 3250) BN 8
J 2
(-2848 3258);
DISPLAY 0.617021 (-2848 3258);
PAINT GREEN (-2848 3258);
FORCEPROP 2 LAST CDS_LIB mstr_standard
J 0
(-2850 3250);
PAINT MONO (-2850 3250);
DISPLAY INVISIBLE (-2850 3250);
FORCEPROP 1 LAST BODY_TYPE PLUMBING
J 2
(-2850 3200);
DISPLAY 1.595745 (-2850 3200);
PAINT GREEN (-2850 3200);
DISPLAY INVISIBLE (-2850 3200);
FORCEPROP 1 LAST HDL_TAP TRUE
J 2
(-3175 3125);
DISPLAY 1.595745 (-3175 3125);
PAINT GREEN (-3175 3125);
DISPLAY INVISIBLE (-3175 3125);
FORCEPROP 1 LAST PATH I133
J 2
(-2848 3250);
DISPLAY 0.872340 (-2848 3250);
PAINT GREEN (-2848 3250);
DISPLAY INVISIBLE (-2848 3250);
FORCEADD TAP..6
R 2
(-2850 3300);
FORCEPROP 3 LASTPIN (-2900 3300) SIG_NAME M_J_DQS_DN<9>
J 0
(-2890 3310);
DISPLAY 0.659574 (-2890 3310);
PAINT MONO (-2890 3310);
DISPLAY INVISIBLE (-2890 3310);
FORCEPROP 1 LASTPIN (-2900 3300) BN 9
J 2
(-2848 3308);
DISPLAY 0.617021 (-2848 3308);
PAINT GREEN (-2848 3308);
FORCEPROP 2 LAST CDS_LIB mstr_standard
J 0
(-2850 3300);
PAINT MONO (-2850 3300);
DISPLAY INVISIBLE (-2850 3300);
FORCEPROP 1 LAST BODY_TYPE PLUMBING
J 2
(-2850 3250);
DISPLAY 1.595745 (-2850 3250);
PAINT GREEN (-2850 3250);
DISPLAY INVISIBLE (-2850 3250);
FORCEPROP 1 LAST HDL_TAP TRUE
J 2
(-3175 3175);
DISPLAY 1.595745 (-3175 3175);
PAINT GREEN (-3175 3175);
DISPLAY INVISIBLE (-3175 3175);
FORCEPROP 1 LAST PATH I134
J 2
(-2848 3300);
DISPLAY 0.872340 (-2848 3300);
PAINT GREEN (-2848 3300);
DISPLAY INVISIBLE (-2848 3300);
FORCEADD TAP..6
R 2
(-2850 3350);
FORCEPROP 3 LASTPIN (-2900 3350) SIG_NAME M_J_DQS_DN<10>
J 0
(-2890 3360);
DISPLAY 0.659574 (-2890 3360);
PAINT MONO (-2890 3360);
DISPLAY INVISIBLE (-2890 3360);
FORCEPROP 1 LASTPIN (-2900 3350) BN 10
J 2
(-2848 3358);
DISPLAY 0.617021 (-2848 3358);
PAINT GREEN (-2848 3358);
FORCEPROP 2 LAST CDS_LIB mstr_standard
J 0
(-2850 3350);
PAINT MONO (-2850 3350);
DISPLAY INVISIBLE (-2850 3350);
FORCEPROP 1 LAST BODY_TYPE PLUMBING
J 2
(-2850 3300);
DISPLAY 1.595745 (-2850 3300);
PAINT GREEN (-2850 3300);
DISPLAY INVISIBLE (-2850 3300);
FORCEPROP 1 LAST HDL_TAP TRUE
J 2
(-3175 3225);
DISPLAY 1.595745 (-3175 3225);
PAINT GREEN (-3175 3225);
DISPLAY INVISIBLE (-3175 3225);
FORCEPROP 1 LAST PATH I135
J 2
(-2848 3350);
DISPLAY 0.872340 (-2848 3350);
PAINT GREEN (-2848 3350);
DISPLAY INVISIBLE (-2848 3350);
FORCEADD TAP..6
R 2
(-2850 3450);
FORCEPROP 3 LASTPIN (-2900 3450) SIG_NAME M_J_DQS_DN<12>
J 0
(-2890 3460);
DISPLAY 0.659574 (-2890 3460);
PAINT MONO (-2890 3460);
DISPLAY INVISIBLE (-2890 3460);
FORCEPROP 1 LASTPIN (-2900 3450) BN 12
J 2
(-2848 3458);
DISPLAY 0.617021 (-2848 3458);
PAINT GREEN (-2848 3458);
FORCEPROP 2 LAST CDS_LIB mstr_standard
J 0
(-2850 3450);
PAINT MONO (-2850 3450);
DISPLAY INVISIBLE (-2850 3450);
FORCEPROP 1 LAST BODY_TYPE PLUMBING
J 2
(-2850 3400);
DISPLAY 1.595745 (-2850 3400);
PAINT GREEN (-2850 3400);
DISPLAY INVISIBLE (-2850 3400);
FORCEPROP 1 LAST HDL_TAP TRUE
J 2
(-3175 3325);
DISPLAY 1.595745 (-3175 3325);
PAINT GREEN (-3175 3325);
DISPLAY INVISIBLE (-3175 3325);
FORCEPROP 1 LAST PATH I136
J 2
(-2848 3450);
DISPLAY 0.872340 (-2848 3450);
PAINT GREEN (-2848 3450);
DISPLAY INVISIBLE (-2848 3450);
FORCEADD TAP..6
R 2
(-2850 3400);
FORCEPROP 3 LASTPIN (-2900 3400) SIG_NAME M_J_DQS_DN<11>
J 0
(-2890 3410);
DISPLAY 0.659574 (-2890 3410);
PAINT MONO (-2890 3410);
DISPLAY INVISIBLE (-2890 3410);
FORCEPROP 1 LASTPIN (-2900 3400) BN 11
J 2
(-2848 3408);
DISPLAY 0.617021 (-2848 3408);
PAINT GREEN (-2848 3408);
FORCEPROP 2 LAST CDS_LIB mstr_standard
J 0
(-2850 3400);
PAINT MONO (-2850 3400);
DISPLAY INVISIBLE (-2850 3400);
FORCEPROP 1 LAST BODY_TYPE PLUMBING
J 2
(-2850 3350);
DISPLAY 1.595745 (-2850 3350);
PAINT GREEN (-2850 3350);
DISPLAY INVISIBLE (-2850 3350);
FORCEPROP 1 LAST HDL_TAP TRUE
J 2
(-3175 3275);
DISPLAY 1.595745 (-3175 3275);
PAINT GREEN (-3175 3275);
DISPLAY INVISIBLE (-3175 3275);
FORCEPROP 1 LAST PATH I137
J 2
(-2848 3400);
DISPLAY 0.872340 (-2848 3400);
PAINT GREEN (-2848 3400);
DISPLAY INVISIBLE (-2848 3400);
FORCEADD TAP..6
R 2
(-2850 3600);
FORCEPROP 3 LASTPIN (-2900 3600) SIG_NAME M_J_DQS_DN<15>
J 0
(-2890 3610);
DISPLAY 0.659574 (-2890 3610);
PAINT MONO (-2890 3610);
DISPLAY INVISIBLE (-2890 3610);
FORCEPROP 1 LASTPIN (-2900 3600) BN 15
J 2
(-2848 3608);
DISPLAY 0.617021 (-2848 3608);
PAINT GREEN (-2848 3608);
FORCEPROP 2 LAST CDS_LIB mstr_standard
J 0
(-2850 3600);
PAINT MONO (-2850 3600);
DISPLAY INVISIBLE (-2850 3600);
FORCEPROP 1 LAST BODY_TYPE PLUMBING
J 2
(-2850 3550);
DISPLAY 1.595745 (-2850 3550);
PAINT GREEN (-2850 3550);
DISPLAY INVISIBLE (-2850 3550);
FORCEPROP 1 LAST HDL_TAP TRUE
J 2
(-3175 3475);
DISPLAY 1.595745 (-3175 3475);
PAINT GREEN (-3175 3475);
DISPLAY INVISIBLE (-3175 3475);
FORCEPROP 1 LAST PATH I138
J 2
(-2848 3600);
DISPLAY 0.872340 (-2848 3600);
PAINT GREEN (-2848 3600);
DISPLAY INVISIBLE (-2848 3600);
FORCEADD TAP..6
R 2
(-2850 3550);
FORCEPROP 3 LASTPIN (-2900 3550) SIG_NAME M_J_DQS_DN<14>
J 0
(-2890 3560);
DISPLAY 0.659574 (-2890 3560);
PAINT MONO (-2890 3560);
DISPLAY INVISIBLE (-2890 3560);
FORCEPROP 1 LASTPIN (-2900 3550) BN 14
J 2
(-2848 3558);
DISPLAY 0.617021 (-2848 3558);
PAINT GREEN (-2848 3558);
FORCEPROP 2 LAST CDS_LIB mstr_standard
J 0
(-2850 3550);
PAINT MONO (-2850 3550);
DISPLAY INVISIBLE (-2850 3550);
FORCEPROP 1 LAST BODY_TYPE PLUMBING
J 2
(-2850 3500);
DISPLAY 1.595745 (-2850 3500);
PAINT GREEN (-2850 3500);
DISPLAY INVISIBLE (-2850 3500);
FORCEPROP 1 LAST HDL_TAP TRUE
J 2
(-3175 3425);
DISPLAY 1.595745 (-3175 3425);
PAINT GREEN (-3175 3425);
DISPLAY INVISIBLE (-3175 3425);
FORCEPROP 1 LAST PATH I139
J 2
(-2848 3550);
DISPLAY 0.872340 (-2848 3550);
PAINT GREEN (-2848 3550);
DISPLAY INVISIBLE (-2848 3550);
FORCEADD TAP..6
(-5575 1100);
FORCEPROP 3 LASTPIN (-5525 1100) SIG_NAME M_J_ECC<1>
J 0
(-5515 1110);
DISPLAY 0.659574 (-5515 1110);
PAINT MONO (-5515 1110);
DISPLAY INVISIBLE (-5515 1110);
FORCEPROP 1 LASTPIN (-5525 1100) BN 1
J 0
(-5577 1108);
DISPLAY 0.617021 (-5577 1108);
PAINT GREEN (-5577 1108);
FORCEPROP 2 LAST CDS_LIB mstr_standard
J 0
(-5575 1100);
PAINT MONO (-5575 1100);
DISPLAY INVISIBLE (-5575 1100);
FORCEPROP 1 LAST BODY_TYPE PLUMBING
J 0
(-5575 1050);
DISPLAY 1.595745 (-5575 1050);
PAINT GREEN (-5575 1050);
DISPLAY INVISIBLE (-5575 1050);
FORCEPROP 1 LAST HDL_TAP TRUE
J 0
(-5250 975);
DISPLAY 1.595745 (-5250 975);
PAINT GREEN (-5250 975);
DISPLAY INVISIBLE (-5250 975);
FORCEPROP 1 LAST PATH I14
J 0
(-5577 1100);
DISPLAY 0.872340 (-5577 1100);
PAINT GREEN (-5577 1100);
DISPLAY INVISIBLE (-5577 1100);
FORCEADD TAP..6
R 2
(-2850 3500);
FORCEPROP 3 LASTPIN (-2900 3500) SIG_NAME M_J_DQS_DN<13>
J 0
(-2890 3510);
DISPLAY 0.659574 (-2890 3510);
PAINT MONO (-2890 3510);
DISPLAY INVISIBLE (-2890 3510);
FORCEPROP 1 LASTPIN (-2900 3500) BN 13
J 2
(-2848 3508);
DISPLAY 0.617021 (-2848 3508);
PAINT GREEN (-2848 3508);
FORCEPROP 2 LAST CDS_LIB mstr_standard
J 0
(-2850 3500);
PAINT MONO (-2850 3500);
DISPLAY INVISIBLE (-2850 3500);
FORCEPROP 1 LAST BODY_TYPE PLUMBING
J 2
(-2850 3450);
DISPLAY 1.595745 (-2850 3450);
PAINT GREEN (-2850 3450);
DISPLAY INVISIBLE (-2850 3450);
FORCEPROP 1 LAST HDL_TAP TRUE
J 2
(-3175 3375);
DISPLAY 1.595745 (-3175 3375);
PAINT GREEN (-3175 3375);
DISPLAY INVISIBLE (-3175 3375);
FORCEPROP 1 LAST PATH I140
J 2
(-2848 3500);
DISPLAY 0.872340 (-2848 3500);
PAINT GREEN (-2848 3500);
DISPLAY INVISIBLE (-2848 3500);
FORCEADD TAP..6
R 2
(-2850 3650);
FORCEPROP 3 LASTPIN (-2900 3650) SIG_NAME M_J_DQS_DN<16>
J 0
(-2890 3660);
DISPLAY 0.659574 (-2890 3660);
PAINT MONO (-2890 3660);
DISPLAY INVISIBLE (-2890 3660);
FORCEPROP 1 LASTPIN (-2900 3650) BN 16
J 2
(-2848 3658);
DISPLAY 0.617021 (-2848 3658);
PAINT GREEN (-2848 3658);
FORCEPROP 2 LAST CDS_LIB mstr_standard
J 0
(-2850 3650);
PAINT MONO (-2850 3650);
DISPLAY INVISIBLE (-2850 3650);
FORCEPROP 1 LAST BODY_TYPE PLUMBING
J 2
(-2850 3600);
DISPLAY 1.595745 (-2850 3600);
PAINT GREEN (-2850 3600);
DISPLAY INVISIBLE (-2850 3600);
FORCEPROP 1 LAST HDL_TAP TRUE
J 2
(-3175 3525);
DISPLAY 1.595745 (-3175 3525);
PAINT GREEN (-3175 3525);
DISPLAY INVISIBLE (-3175 3525);
FORCEPROP 1 LAST PATH I141
J 2
(-2848 3650);
DISPLAY 0.872340 (-2848 3650);
PAINT GREEN (-2848 3650);
DISPLAY INVISIBLE (-2848 3650);
FORCEADD TAP..6
R 2
(-2850 3700);
FORCEPROP 3 LASTPIN (-2900 3700) SIG_NAME M_J_DQS_DN<17>
J 0
(-2890 3710);
DISPLAY 0.659574 (-2890 3710);
PAINT MONO (-2890 3710);
DISPLAY INVISIBLE (-2890 3710);
FORCEPROP 1 LASTPIN (-2900 3700) BN 17
J 2
(-2848 3708);
DISPLAY 0.617021 (-2848 3708);
PAINT GREEN (-2848 3708);
FORCEPROP 2 LAST CDS_LIB mstr_standard
J 0
(-2850 3700);
PAINT MONO (-2850 3700);
DISPLAY INVISIBLE (-2850 3700);
FORCEPROP 1 LAST BODY_TYPE PLUMBING
J 2
(-2850 3650);
DISPLAY 1.595745 (-2850 3650);
PAINT GREEN (-2850 3650);
DISPLAY INVISIBLE (-2850 3650);
FORCEPROP 1 LAST HDL_TAP TRUE
J 2
(-3175 3575);
DISPLAY 1.595745 (-3175 3575);
PAINT GREEN (-3175 3575);
DISPLAY INVISIBLE (-3175 3575);
FORCEPROP 1 LAST PATH I142
J 2
(-2848 3700);
DISPLAY 0.872340 (-2848 3700);
PAINT GREEN (-2848 3700);
DISPLAY INVISIBLE (-2848 3700);
FORCEADD TAP..6
R 2
(-2850 3800);
FORCEPROP 3 LASTPIN (-2900 3800) SIG_NAME M_J_DQS_DP<0>
J 0
(-2890 3810);
DISPLAY 0.659574 (-2890 3810);
PAINT MONO (-2890 3810);
DISPLAY INVISIBLE (-2890 3810);
FORCEPROP 1 LASTPIN (-2900 3800) BN 0
J 2
(-2848 3808);
DISPLAY 0.617021 (-2848 3808);
PAINT GREEN (-2848 3808);
FORCEPROP 2 LAST CDS_LIB mstr_standard
J 0
(-2850 3800);
PAINT MONO (-2850 3800);
DISPLAY INVISIBLE (-2850 3800);
FORCEPROP 1 LAST BODY_TYPE PLUMBING
J 2
(-2850 3750);
DISPLAY 1.595745 (-2850 3750);
PAINT GREEN (-2850 3750);
DISPLAY INVISIBLE (-2850 3750);
FORCEPROP 1 LAST HDL_TAP TRUE
J 2
(-3175 3675);
DISPLAY 1.595745 (-3175 3675);
PAINT GREEN (-3175 3675);
DISPLAY INVISIBLE (-3175 3675);
FORCEPROP 1 LAST PATH I143
J 2
(-2848 3800);
DISPLAY 0.872340 (-2848 3800);
PAINT GREEN (-2848 3800);
DISPLAY INVISIBLE (-2848 3800);
FORCEADD TAP..6
R 2
(-2850 3850);
FORCEPROP 3 LASTPIN (-2900 3850) SIG_NAME M_J_DQS_DP<1>
J 0
(-2890 3860);
DISPLAY 0.659574 (-2890 3860);
PAINT MONO (-2890 3860);
DISPLAY INVISIBLE (-2890 3860);
FORCEPROP 1 LASTPIN (-2900 3850) BN 1
J 2
(-2848 3858);
DISPLAY 0.617021 (-2848 3858);
PAINT GREEN (-2848 3858);
FORCEPROP 2 LAST CDS_LIB mstr_standard
J 0
(-2850 3850);
PAINT MONO (-2850 3850);
DISPLAY INVISIBLE (-2850 3850);
FORCEPROP 1 LAST BODY_TYPE PLUMBING
J 2
(-2850 3800);
DISPLAY 1.595745 (-2850 3800);
PAINT GREEN (-2850 3800);
DISPLAY INVISIBLE (-2850 3800);
FORCEPROP 1 LAST HDL_TAP TRUE
J 2
(-3175 3725);
DISPLAY 1.595745 (-3175 3725);
PAINT GREEN (-3175 3725);
DISPLAY INVISIBLE (-3175 3725);
FORCEPROP 1 LAST PATH I144
J 2
(-2848 3850);
DISPLAY 0.872340 (-2848 3850);
PAINT GREEN (-2848 3850);
DISPLAY INVISIBLE (-2848 3850);
FORCEADD TAP..6
R 2
(-2850 3900);
FORCEPROP 3 LASTPIN (-2900 3900) SIG_NAME M_J_DQS_DP<2>
J 0
(-2890 3910);
DISPLAY 0.659574 (-2890 3910);
PAINT MONO (-2890 3910);
DISPLAY INVISIBLE (-2890 3910);
FORCEPROP 1 LASTPIN (-2900 3900) BN 2
J 2
(-2848 3908);
DISPLAY 0.617021 (-2848 3908);
PAINT GREEN (-2848 3908);
FORCEPROP 2 LAST CDS_LIB mstr_standard
J 0
(-2850 3900);
PAINT MONO (-2850 3900);
DISPLAY INVISIBLE (-2850 3900);
FORCEPROP 1 LAST BODY_TYPE PLUMBING
J 2
(-2850 3850);
DISPLAY 1.595745 (-2850 3850);
PAINT GREEN (-2850 3850);
DISPLAY INVISIBLE (-2850 3850);
FORCEPROP 1 LAST HDL_TAP TRUE
J 2
(-3175 3775);
DISPLAY 1.595745 (-3175 3775);
PAINT GREEN (-3175 3775);
DISPLAY INVISIBLE (-3175 3775);
FORCEPROP 1 LAST PATH I145
J 2
(-2848 3900);
DISPLAY 0.872340 (-2848 3900);
PAINT GREEN (-2848 3900);
DISPLAY INVISIBLE (-2848 3900);
FORCEADD TAP..6
R 2
(-2850 3950);
FORCEPROP 3 LASTPIN (-2900 3950) SIG_NAME M_J_DQS_DP<3>
J 0
(-2890 3960);
DISPLAY 0.659574 (-2890 3960);
PAINT MONO (-2890 3960);
DISPLAY INVISIBLE (-2890 3960);
FORCEPROP 1 LASTPIN (-2900 3950) BN 3
J 2
(-2848 3958);
DISPLAY 0.617021 (-2848 3958);
PAINT GREEN (-2848 3958);
FORCEPROP 2 LAST CDS_LIB mstr_standard
J 0
(-2850 3950);
PAINT MONO (-2850 3950);
DISPLAY INVISIBLE (-2850 3950);
FORCEPROP 1 LAST BODY_TYPE PLUMBING
J 2
(-2850 3900);
DISPLAY 1.595745 (-2850 3900);
PAINT GREEN (-2850 3900);
DISPLAY INVISIBLE (-2850 3900);
FORCEPROP 1 LAST HDL_TAP TRUE
J 2
(-3175 3825);
DISPLAY 1.595745 (-3175 3825);
PAINT GREEN (-3175 3825);
DISPLAY INVISIBLE (-3175 3825);
FORCEPROP 1 LAST PATH I146
J 2
(-2848 3950);
DISPLAY 0.872340 (-2848 3950);
PAINT GREEN (-2848 3950);
DISPLAY INVISIBLE (-2848 3950);
FORCEADD OFFPAGE..2
(-1975 500);
FORCEPROP 2 LAST $XR1 82 
J 0
(-1696 500);
DISPLAY 0.638298 (-1696 500);
PAINT MONO (-1696 500);
FORCEPROP 2 LAST $XR0 81 
J 0
(-1786 500);
DISPLAY 0.638298 (-1786 500);
PAINT MONO (-1786 500);
FORCEPROP 2 LAST CDS_LIB mstr_standard
J 0
(-1975 500);
PAINT MONO (-1975 500);
DISPLAY INVISIBLE (-1975 500);
FORCEPROP 1 LAST OFFPAGE TRUE
J 0
(-1650 375);
DISPLAY 1.170213 (-1650 375);
PAINT GREEN (-1650 375);
DISPLAY INVISIBLE (-1650 375);
FORCEPROP 1 LAST COMMENT_BODY TRUE
J 0
(-2020 405);
DISPLAY 1.170213 (-2020 405);
PAINT GREEN (-2020 405);
DISPLAY INVISIBLE (-2020 405);
FORCEPROP 2 LAST PATH I147
J 0
(-1800 575);
DISPLAY 1.021277 (-1800 575);
PAINT ORANGE (-1800 575);
DISPLAY INVISIBLE (-1800 575);
FORCEADD OFFPAGE..4
(-1975 550);
FORCEPROP 2 LAST $XR1 82 
J 0
(-1699 550);
DISPLAY 0.638298 (-1699 550);
PAINT MONO (-1699 550);
FORCEPROP 2 LAST $XR0 81 
J 0
(-1789 550);
DISPLAY 0.638298 (-1789 550);
PAINT MONO (-1789 550);
FORCEPROP 2 LAST CDS_LIB mstr_standard
J 0
(-1975 550);
PAINT MONO (-1975 550);
DISPLAY INVISIBLE (-1975 550);
FORCEPROP 1 LAST OFFPAGE TRUE
J 0
(-1650 425);
DISPLAY 1.170213 (-1650 425);
PAINT GREEN (-1650 425);
DISPLAY INVISIBLE (-1650 425);
FORCEPROP 1 LAST COMMENT_BODY TRUE
J 0
(-2000 450);
DISPLAY 1.170213 (-2000 450);
PAINT GREEN (-2000 450);
DISPLAY INVISIBLE (-2000 450);
FORCEPROP 2 LAST PATH I148
J 0
(-1800 625);
DISPLAY 1.021277 (-1800 625);
PAINT ORANGE (-1800 625);
DISPLAY INVISIBLE (-1800 625);
FORCEADD OFFPAGE..2
(-1975 600);
FORCEPROP 2 LAST $XR1 82 
J 0
(-1696 600);
DISPLAY 0.638298 (-1696 600);
PAINT MONO (-1696 600);
FORCEPROP 2 LAST $XR0 81 
J 0
(-1786 600);
DISPLAY 0.638298 (-1786 600);
PAINT MONO (-1786 600);
FORCEPROP 2 LAST CDS_LIB mstr_standard
J 0
(-1975 600);
PAINT MONO (-1975 600);
DISPLAY INVISIBLE (-1975 600);
FORCEPROP 1 LAST OFFPAGE TRUE
J 0
(-1650 475);
DISPLAY 1.170213 (-1650 475);
PAINT GREEN (-1650 475);
DISPLAY INVISIBLE (-1650 475);
FORCEPROP 1 LAST COMMENT_BODY TRUE
J 0
(-2020 505);
DISPLAY 1.170213 (-2020 505);
PAINT GREEN (-2020 505);
DISPLAY INVISIBLE (-2020 505);
FORCEPROP 2 LAST PATH I149
J 0
(-1800 675);
DISPLAY 1.021277 (-1800 675);
PAINT ORANGE (-1800 675);
DISPLAY INVISIBLE (-1800 675);
FORCEADD TAP..6
(-5575 1150);
FORCEPROP 3 LASTPIN (-5525 1150) SIG_NAME M_J_ECC<2>
J 0
(-5515 1160);
DISPLAY 0.659574 (-5515 1160);
PAINT MONO (-5515 1160);
DISPLAY INVISIBLE (-5515 1160);
FORCEPROP 1 LASTPIN (-5525 1150) BN 2
J 0
(-5577 1158);
DISPLAY 0.617021 (-5577 1158);
PAINT GREEN (-5577 1158);
FORCEPROP 2 LAST CDS_LIB mstr_standard
J 0
(-5575 1150);
PAINT MONO (-5575 1150);
DISPLAY INVISIBLE (-5575 1150);
FORCEPROP 1 LAST BODY_TYPE PLUMBING
J 0
(-5575 1100);
DISPLAY 1.595745 (-5575 1100);
PAINT GREEN (-5575 1100);
DISPLAY INVISIBLE (-5575 1100);
FORCEPROP 1 LAST HDL_TAP TRUE
J 0
(-5250 1025);
DISPLAY 1.595745 (-5250 1025);
PAINT GREEN (-5250 1025);
DISPLAY INVISIBLE (-5250 1025);
FORCEPROP 1 LAST PATH I15
J 0
(-5577 1150);
DISPLAY 0.872340 (-5577 1150);
PAINT GREEN (-5577 1150);
DISPLAY INVISIBLE (-5577 1150);
FORCEADD OFFPAGE..2
(-2000 800);
FORCEPROP 2 LAST $XR1 82 
J 0
(-1721 800);
DISPLAY 0.638298 (-1721 800);
PAINT MONO (-1721 800);
FORCEPROP 2 LAST $XR0 81 
J 0
(-1811 800);
DISPLAY 0.638298 (-1811 800);
PAINT MONO (-1811 800);
FORCEPROP 2 LAST CDS_LIB mstr_standard
J 0
(-2000 800);
PAINT MONO (-2000 800);
DISPLAY INVISIBLE (-2000 800);
FORCEPROP 1 LAST OFFPAGE TRUE
J 0
(-1675 675);
DISPLAY 1.170213 (-1675 675);
PAINT GREEN (-1675 675);
DISPLAY INVISIBLE (-1675 675);
FORCEPROP 1 LAST COMMENT_BODY TRUE
J 0
(-2045 705);
DISPLAY 1.170213 (-2045 705);
PAINT GREEN (-2045 705);
DISPLAY INVISIBLE (-2045 705);
FORCEPROP 2 LAST PATH I150
J 0
(-1825 875);
DISPLAY 1.021277 (-1825 875);
PAINT ORANGE (-1825 875);
DISPLAY INVISIBLE (-1825 875);
FORCEADD OFFPAGE..2
(-2000 900);
FORCEPROP 2 LAST $XR1 82 
J 0
(-1721 900);
DISPLAY 0.638298 (-1721 900);
PAINT MONO (-1721 900);
FORCEPROP 2 LAST $XR0 81 
J 0
(-1811 900);
DISPLAY 0.638298 (-1811 900);
PAINT MONO (-1811 900);
FORCEPROP 2 LAST CDS_LIB mstr_standard
J 0
(-2000 900);
PAINT MONO (-2000 900);
DISPLAY INVISIBLE (-2000 900);
FORCEPROP 1 LAST OFFPAGE TRUE
J 0
(-1675 775);
DISPLAY 1.170213 (-1675 775);
PAINT GREEN (-1675 775);
DISPLAY INVISIBLE (-1675 775);
FORCEPROP 1 LAST COMMENT_BODY TRUE
J 0
(-2045 805);
DISPLAY 1.170213 (-2045 805);
PAINT GREEN (-2045 805);
DISPLAY INVISIBLE (-2045 805);
FORCEPROP 2 LAST PATH I151
J 0
(-1825 975);
DISPLAY 1.021277 (-1825 975);
PAINT ORANGE (-1825 975);
DISPLAY INVISIBLE (-1825 975);
FORCEADD OFFPAGE..2
(-2000 1350);
FORCEPROP 2 LAST $XR1 82 
J 0
(-1721 1350);
DISPLAY 0.638298 (-1721 1350);
PAINT MONO (-1721 1350);
FORCEPROP 2 LAST $XR0 81 
J 0
(-1811 1350);
DISPLAY 0.638298 (-1811 1350);
PAINT MONO (-1811 1350);
FORCEPROP 2 LAST CDS_LIB mstr_standard
J 0
(-2000 1350);
PAINT MONO (-2000 1350);
DISPLAY INVISIBLE (-2000 1350);
FORCEPROP 1 LAST OFFPAGE TRUE
J 0
(-1675 1225);
DISPLAY 1.170213 (-1675 1225);
PAINT GREEN (-1675 1225);
DISPLAY INVISIBLE (-1675 1225);
FORCEPROP 1 LAST COMMENT_BODY TRUE
J 0
(-2045 1255);
DISPLAY 1.170213 (-2045 1255);
PAINT GREEN (-2045 1255);
DISPLAY INVISIBLE (-2045 1255);
FORCEPROP 2 LAST PATH I152
J 0
(-1825 1425);
DISPLAY 1.021277 (-1825 1425);
PAINT ORANGE (-1825 1425);
DISPLAY INVISIBLE (-1825 1425);
FORCEADD OFFPAGE..2
(-2000 1600);
FORCEPROP 2 LAST $XR1 82 
J 0
(-1721 1600);
DISPLAY 0.638298 (-1721 1600);
PAINT MONO (-1721 1600);
FORCEPROP 2 LAST $XR0 81 
J 0
(-1811 1600);
DISPLAY 0.638298 (-1811 1600);
PAINT MONO (-1811 1600);
FORCEPROP 2 LAST CDS_LIB mstr_standard
J 0
(-2000 1600);
PAINT MONO (-2000 1600);
DISPLAY INVISIBLE (-2000 1600);
FORCEPROP 1 LAST OFFPAGE TRUE
J 0
(-1675 1475);
DISPLAY 1.170213 (-1675 1475);
PAINT GREEN (-1675 1475);
DISPLAY INVISIBLE (-1675 1475);
FORCEPROP 1 LAST COMMENT_BODY TRUE
J 0
(-2045 1505);
DISPLAY 1.170213 (-2045 1505);
PAINT GREEN (-2045 1505);
DISPLAY INVISIBLE (-2045 1505);
FORCEPROP 2 LAST PATH I153
J 0
(-1825 1675);
DISPLAY 1.021277 (-1825 1675);
PAINT ORANGE (-1825 1675);
DISPLAY INVISIBLE (-1825 1675);
FORCEADD OFFPAGE..2
(-2000 1850);
FORCEPROP 2 LAST $XR1 82 
J 0
(-1721 1850);
DISPLAY 0.638298 (-1721 1850);
PAINT MONO (-1721 1850);
FORCEPROP 2 LAST $XR0 81 
J 0
(-1811 1850);
DISPLAY 0.638298 (-1811 1850);
PAINT MONO (-1811 1850);
FORCEPROP 2 LAST CDS_LIB mstr_standard
J 0
(-2000 1850);
PAINT MONO (-2000 1850);
DISPLAY INVISIBLE (-2000 1850);
FORCEPROP 1 LAST OFFPAGE TRUE
J 0
(-1675 1725);
DISPLAY 1.170213 (-1675 1725);
PAINT GREEN (-1675 1725);
DISPLAY INVISIBLE (-1675 1725);
FORCEPROP 1 LAST COMMENT_BODY TRUE
J 0
(-2045 1755);
DISPLAY 1.170213 (-2045 1755);
PAINT GREEN (-2045 1755);
DISPLAY INVISIBLE (-2045 1755);
FORCEPROP 2 LAST PATH I154
J 0
(-1825 1925);
DISPLAY 1.021277 (-1825 1925);
PAINT ORANGE (-1825 1925);
DISPLAY INVISIBLE (-1825 1925);
FORCEADD OFFPAGE..2
(-2000 2800);
FORCEPROP 2 LAST $XR1 82 
J 0
(-1721 2800);
DISPLAY 0.638298 (-1721 2800);
PAINT MONO (-1721 2800);
FORCEPROP 2 LAST $XR0 81 
J 0
(-1811 2800);
DISPLAY 0.638298 (-1811 2800);
PAINT MONO (-1811 2800);
FORCEPROP 2 LAST CDS_LIB mstr_standard
J 0
(-2000 2800);
PAINT MONO (-2000 2800);
DISPLAY INVISIBLE (-2000 2800);
FORCEPROP 1 LAST OFFPAGE TRUE
J 0
(-1675 2675);
DISPLAY 1.170213 (-1675 2675);
PAINT GREEN (-1675 2675);
DISPLAY INVISIBLE (-1675 2675);
FORCEPROP 1 LAST COMMENT_BODY TRUE
J 0
(-2045 2705);
DISPLAY 1.170213 (-2045 2705);
PAINT GREEN (-2045 2705);
DISPLAY INVISIBLE (-2045 2705);
FORCEPROP 2 LAST PATH I155
J 0
(-1825 2875);
DISPLAY 1.021277 (-1825 2875);
PAINT ORANGE (-1825 2875);
DISPLAY INVISIBLE (-1825 2875);
FORCEADD OFFPAGE..3
(-2000 3750);
FORCEPROP 2 LAST $XR1 82 
J 0
(-1696 3750);
DISPLAY 0.638298 (-1696 3750);
PAINT MONO (-1696 3750);
FORCEPROP 2 LAST $XR0 81 
J 0
(-1786 3750);
DISPLAY 0.638298 (-1786 3750);
PAINT MONO (-1786 3750);
FORCEPROP 2 LAST CDS_LIB mstr_standard
J 0
(-2000 3750);
PAINT MONO (-2000 3750);
DISPLAY INVISIBLE (-2000 3750);
FORCEPROP 1 LAST OFFPAGE TRUE
J 0
(-1675 3625);
DISPLAY 1.170213 (-1675 3625);
PAINT GREEN (-1675 3625);
DISPLAY INVISIBLE (-1675 3625);
FORCEPROP 1 LAST COMMENT_BODY TRUE
J 0
(-2050 3650);
DISPLAY 1.170213 (-2050 3650);
PAINT GREEN (-2050 3650);
DISPLAY INVISIBLE (-2050 3650);
FORCEPROP 2 LAST PATH I156
J 0
(-1800 3825);
DISPLAY 1.021277 (-1800 3825);
PAINT ORANGE (-1800 3825);
DISPLAY INVISIBLE (-1800 3825);
FORCEADD TAP..6
R 2
(-2850 4000);
FORCEPROP 3 LASTPIN (-2900 4000) SIG_NAME M_J_DQS_DP<4>
J 0
(-2890 4010);
DISPLAY 0.659574 (-2890 4010);
PAINT MONO (-2890 4010);
DISPLAY INVISIBLE (-2890 4010);
FORCEPROP 1 LASTPIN (-2900 4000) BN 4
J 2
(-2848 4008);
DISPLAY 0.617021 (-2848 4008);
PAINT GREEN (-2848 4008);
FORCEPROP 2 LAST CDS_LIB mstr_standard
J 0
(-2850 4000);
PAINT MONO (-2850 4000);
DISPLAY INVISIBLE (-2850 4000);
FORCEPROP 1 LAST BODY_TYPE PLUMBING
J 2
(-2850 3950);
DISPLAY 1.595745 (-2850 3950);
PAINT GREEN (-2850 3950);
DISPLAY INVISIBLE (-2850 3950);
FORCEPROP 1 LAST HDL_TAP TRUE
J 2
(-3175 3875);
DISPLAY 1.595745 (-3175 3875);
PAINT GREEN (-3175 3875);
DISPLAY INVISIBLE (-3175 3875);
FORCEPROP 1 LAST PATH I157
J 2
(-2848 4000);
DISPLAY 0.872340 (-2848 4000);
PAINT GREEN (-2848 4000);
DISPLAY INVISIBLE (-2848 4000);
FORCEADD TAP..6
R 2
(-2850 4100);
FORCEPROP 3 LASTPIN (-2900 4100) SIG_NAME M_J_DQS_DP<6>
J 0
(-2890 4110);
DISPLAY 0.659574 (-2890 4110);
PAINT MONO (-2890 4110);
DISPLAY INVISIBLE (-2890 4110);
FORCEPROP 1 LASTPIN (-2900 4100) BN 6
J 2
(-2848 4108);
DISPLAY 0.617021 (-2848 4108);
PAINT GREEN (-2848 4108);
FORCEPROP 2 LAST CDS_LIB mstr_standard
J 0
(-2850 4100);
PAINT MONO (-2850 4100);
DISPLAY INVISIBLE (-2850 4100);
FORCEPROP 1 LAST BODY_TYPE PLUMBING
J 2
(-2850 4050);
DISPLAY 1.595745 (-2850 4050);
PAINT GREEN (-2850 4050);
DISPLAY INVISIBLE (-2850 4050);
FORCEPROP 1 LAST HDL_TAP TRUE
J 2
(-3175 3975);
DISPLAY 1.595745 (-3175 3975);
PAINT GREEN (-3175 3975);
DISPLAY INVISIBLE (-3175 3975);
FORCEPROP 1 LAST PATH I158
J 2
(-2848 4100);
DISPLAY 0.872340 (-2848 4100);
PAINT GREEN (-2848 4100);
DISPLAY INVISIBLE (-2848 4100);
FORCEADD TAP..6
R 2
(-2850 4050);
FORCEPROP 3 LASTPIN (-2900 4050) SIG_NAME M_J_DQS_DP<5>
J 0
(-2890 4060);
DISPLAY 0.659574 (-2890 4060);
PAINT MONO (-2890 4060);
DISPLAY INVISIBLE (-2890 4060);
FORCEPROP 1 LASTPIN (-2900 4050) BN 5
J 2
(-2848 4058);
DISPLAY 0.617021 (-2848 4058);
PAINT GREEN (-2848 4058);
FORCEPROP 2 LAST CDS_LIB mstr_standard
J 0
(-2850 4050);
PAINT MONO (-2850 4050);
DISPLAY INVISIBLE (-2850 4050);
FORCEPROP 1 LAST BODY_TYPE PLUMBING
J 2
(-2850 4000);
DISPLAY 1.595745 (-2850 4000);
PAINT GREEN (-2850 4000);
DISPLAY INVISIBLE (-2850 4000);
FORCEPROP 1 LAST HDL_TAP TRUE
J 2
(-3175 3925);
DISPLAY 1.595745 (-3175 3925);
PAINT GREEN (-3175 3925);
DISPLAY INVISIBLE (-3175 3925);
FORCEPROP 1 LAST PATH I159
J 2
(-2848 4050);
DISPLAY 0.872340 (-2848 4050);
PAINT GREEN (-2848 4050);
DISPLAY INVISIBLE (-2848 4050);
FORCEADD TAP..6
(-5575 1250);
FORCEPROP 3 LASTPIN (-5525 1250) SIG_NAME M_J_ECC<4>
J 0
(-5515 1260);
DISPLAY 0.659574 (-5515 1260);
PAINT MONO (-5515 1260);
DISPLAY INVISIBLE (-5515 1260);
FORCEPROP 1 LASTPIN (-5525 1250) BN 4
J 0
(-5577 1258);
DISPLAY 0.617021 (-5577 1258);
PAINT GREEN (-5577 1258);
FORCEPROP 2 LAST CDS_LIB mstr_standard
J 0
(-5575 1250);
PAINT MONO (-5575 1250);
DISPLAY INVISIBLE (-5575 1250);
FORCEPROP 1 LAST BODY_TYPE PLUMBING
J 0
(-5575 1200);
DISPLAY 1.595745 (-5575 1200);
PAINT GREEN (-5575 1200);
DISPLAY INVISIBLE (-5575 1200);
FORCEPROP 1 LAST HDL_TAP TRUE
J 0
(-5250 1125);
DISPLAY 1.595745 (-5250 1125);
PAINT GREEN (-5250 1125);
DISPLAY INVISIBLE (-5250 1125);
FORCEPROP 1 LAST PATH I16
J 0
(-5577 1250);
DISPLAY 0.872340 (-5577 1250);
PAINT GREEN (-5577 1250);
DISPLAY INVISIBLE (-5577 1250);
FORCEADD TAP..6
R 2
(-2850 4150);
FORCEPROP 3 LASTPIN (-2900 4150) SIG_NAME M_J_DQS_DP<7>
J 0
(-2890 4160);
DISPLAY 0.659574 (-2890 4160);
PAINT MONO (-2890 4160);
DISPLAY INVISIBLE (-2890 4160);
FORCEPROP 1 LASTPIN (-2900 4150) BN 7
J 2
(-2848 4158);
DISPLAY 0.617021 (-2848 4158);
PAINT GREEN (-2848 4158);
FORCEPROP 2 LAST CDS_LIB mstr_standard
J 0
(-2850 4150);
PAINT MONO (-2850 4150);
DISPLAY INVISIBLE (-2850 4150);
FORCEPROP 1 LAST BODY_TYPE PLUMBING
J 2
(-2850 4100);
DISPLAY 1.595745 (-2850 4100);
PAINT GREEN (-2850 4100);
DISPLAY INVISIBLE (-2850 4100);
FORCEPROP 1 LAST HDL_TAP TRUE
J 2
(-3175 4025);
DISPLAY 1.595745 (-3175 4025);
PAINT GREEN (-3175 4025);
DISPLAY INVISIBLE (-3175 4025);
FORCEPROP 1 LAST PATH I160
J 2
(-2848 4150);
DISPLAY 0.872340 (-2848 4150);
PAINT GREEN (-2848 4150);
DISPLAY INVISIBLE (-2848 4150);
FORCEADD TAP..6
R 2
(-2850 4200);
FORCEPROP 3 LASTPIN (-2900 4200) SIG_NAME M_J_DQS_DP<8>
J 0
(-2890 4210);
DISPLAY 0.659574 (-2890 4210);
PAINT MONO (-2890 4210);
DISPLAY INVISIBLE (-2890 4210);
FORCEPROP 1 LASTPIN (-2900 4200) BN 8
J 2
(-2848 4208);
DISPLAY 0.617021 (-2848 4208);
PAINT GREEN (-2848 4208);
FORCEPROP 2 LAST CDS_LIB mstr_standard
J 0
(-2850 4200);
PAINT MONO (-2850 4200);
DISPLAY INVISIBLE (-2850 4200);
FORCEPROP 1 LAST BODY_TYPE PLUMBING
J 2
(-2850 4150);
DISPLAY 1.595745 (-2850 4150);
PAINT GREEN (-2850 4150);
DISPLAY INVISIBLE (-2850 4150);
FORCEPROP 1 LAST HDL_TAP TRUE
J 2
(-3175 4075);
DISPLAY 1.595745 (-3175 4075);
PAINT GREEN (-3175 4075);
DISPLAY INVISIBLE (-3175 4075);
FORCEPROP 1 LAST PATH I161
J 2
(-2848 4200);
DISPLAY 0.872340 (-2848 4200);
PAINT GREEN (-2848 4200);
DISPLAY INVISIBLE (-2848 4200);
FORCEADD TAP..6
R 2
(-2850 4250);
FORCEPROP 3 LASTPIN (-2900 4250) SIG_NAME M_J_DQS_DP<9>
J 0
(-2890 4260);
DISPLAY 0.659574 (-2890 4260);
PAINT MONO (-2890 4260);
DISPLAY INVISIBLE (-2890 4260);
FORCEPROP 1 LASTPIN (-2900 4250) BN 9
J 2
(-2848 4258);
DISPLAY 0.617021 (-2848 4258);
PAINT GREEN (-2848 4258);
FORCEPROP 2 LAST CDS_LIB mstr_standard
J 0
(-2850 4250);
PAINT MONO (-2850 4250);
DISPLAY INVISIBLE (-2850 4250);
FORCEPROP 1 LAST BODY_TYPE PLUMBING
J 2
(-2850 4200);
DISPLAY 1.595745 (-2850 4200);
PAINT GREEN (-2850 4200);
DISPLAY INVISIBLE (-2850 4200);
FORCEPROP 1 LAST HDL_TAP TRUE
J 2
(-3175 4125);
DISPLAY 1.595745 (-3175 4125);
PAINT GREEN (-3175 4125);
DISPLAY INVISIBLE (-3175 4125);
FORCEPROP 1 LAST PATH I162
J 2
(-2848 4250);
DISPLAY 0.872340 (-2848 4250);
PAINT GREEN (-2848 4250);
DISPLAY INVISIBLE (-2848 4250);
FORCEADD TAP..6
R 2
(-2850 4300);
FORCEPROP 3 LASTPIN (-2900 4300) SIG_NAME M_J_DQS_DP<10>
J 0
(-2890 4310);
DISPLAY 0.659574 (-2890 4310);
PAINT MONO (-2890 4310);
DISPLAY INVISIBLE (-2890 4310);
FORCEPROP 1 LASTPIN (-2900 4300) BN 10
J 2
(-2848 4308);
DISPLAY 0.617021 (-2848 4308);
PAINT GREEN (-2848 4308);
FORCEPROP 2 LAST CDS_LIB mstr_standard
J 0
(-2850 4300);
PAINT MONO (-2850 4300);
DISPLAY INVISIBLE (-2850 4300);
FORCEPROP 1 LAST BODY_TYPE PLUMBING
J 2
(-2850 4250);
DISPLAY 1.595745 (-2850 4250);
PAINT GREEN (-2850 4250);
DISPLAY INVISIBLE (-2850 4250);
FORCEPROP 1 LAST HDL_TAP TRUE
J 2
(-3175 4175);
DISPLAY 1.595745 (-3175 4175);
PAINT GREEN (-3175 4175);
DISPLAY INVISIBLE (-3175 4175);
FORCEPROP 1 LAST PATH I163
J 2
(-2848 4300);
DISPLAY 0.872340 (-2848 4300);
PAINT GREEN (-2848 4300);
DISPLAY INVISIBLE (-2848 4300);
FORCEADD TAP..6
R 2
(-2850 4350);
FORCEPROP 3 LASTPIN (-2900 4350) SIG_NAME M_J_DQS_DP<11>
J 0
(-2890 4360);
DISPLAY 0.659574 (-2890 4360);
PAINT MONO (-2890 4360);
DISPLAY INVISIBLE (-2890 4360);
FORCEPROP 1 LASTPIN (-2900 4350) BN 11
J 2
(-2848 4358);
DISPLAY 0.617021 (-2848 4358);
PAINT GREEN (-2848 4358);
FORCEPROP 2 LAST CDS_LIB mstr_standard
J 0
(-2850 4350);
PAINT MONO (-2850 4350);
DISPLAY INVISIBLE (-2850 4350);
FORCEPROP 1 LAST BODY_TYPE PLUMBING
J 2
(-2850 4300);
DISPLAY 1.595745 (-2850 4300);
PAINT GREEN (-2850 4300);
DISPLAY INVISIBLE (-2850 4300);
FORCEPROP 1 LAST HDL_TAP TRUE
J 2
(-3175 4225);
DISPLAY 1.595745 (-3175 4225);
PAINT GREEN (-3175 4225);
DISPLAY INVISIBLE (-3175 4225);
FORCEPROP 1 LAST PATH I164
J 2
(-2848 4350);
DISPLAY 0.872340 (-2848 4350);
PAINT GREEN (-2848 4350);
DISPLAY INVISIBLE (-2848 4350);
FORCEADD TAP..6
R 2
(-2850 4500);
FORCEPROP 3 LASTPIN (-2900 4500) SIG_NAME M_J_DQS_DP<14>
J 0
(-2890 4510);
DISPLAY 0.659574 (-2890 4510);
PAINT MONO (-2890 4510);
DISPLAY INVISIBLE (-2890 4510);
FORCEPROP 1 LASTPIN (-2900 4500) BN 14
J 2
(-2848 4508);
DISPLAY 0.617021 (-2848 4508);
PAINT GREEN (-2848 4508);
FORCEPROP 2 LAST CDS_LIB mstr_standard
J 0
(-2850 4500);
PAINT MONO (-2850 4500);
DISPLAY INVISIBLE (-2850 4500);
FORCEPROP 1 LAST BODY_TYPE PLUMBING
J 2
(-2850 4450);
DISPLAY 1.595745 (-2850 4450);
PAINT GREEN (-2850 4450);
DISPLAY INVISIBLE (-2850 4450);
FORCEPROP 1 LAST HDL_TAP TRUE
J 2
(-3175 4375);
DISPLAY 1.595745 (-3175 4375);
PAINT GREEN (-3175 4375);
DISPLAY INVISIBLE (-3175 4375);
FORCEPROP 1 LAST PATH I165
J 2
(-2848 4500);
DISPLAY 0.872340 (-2848 4500);
PAINT GREEN (-2848 4500);
DISPLAY INVISIBLE (-2848 4500);
FORCEADD TAP..6
R 2
(-2850 4450);
FORCEPROP 3 LASTPIN (-2900 4450) SIG_NAME M_J_DQS_DP<13>
J 0
(-2890 4460);
DISPLAY 0.659574 (-2890 4460);
PAINT MONO (-2890 4460);
DISPLAY INVISIBLE (-2890 4460);
FORCEPROP 1 LASTPIN (-2900 4450) BN 13
J 2
(-2848 4458);
DISPLAY 0.617021 (-2848 4458);
PAINT GREEN (-2848 4458);
FORCEPROP 2 LAST CDS_LIB mstr_standard
J 0
(-2850 4450);
PAINT MONO (-2850 4450);
DISPLAY INVISIBLE (-2850 4450);
FORCEPROP 1 LAST BODY_TYPE PLUMBING
J 2
(-2850 4400);
DISPLAY 1.595745 (-2850 4400);
PAINT GREEN (-2850 4400);
DISPLAY INVISIBLE (-2850 4400);
FORCEPROP 1 LAST HDL_TAP TRUE
J 2
(-3175 4325);
DISPLAY 1.595745 (-3175 4325);
PAINT GREEN (-3175 4325);
DISPLAY INVISIBLE (-3175 4325);
FORCEPROP 1 LAST PATH I166
J 2
(-2848 4450);
DISPLAY 0.872340 (-2848 4450);
PAINT GREEN (-2848 4450);
DISPLAY INVISIBLE (-2848 4450);
FORCEADD TAP..6
R 2
(-2850 4400);
FORCEPROP 3 LASTPIN (-2900 4400) SIG_NAME M_J_DQS_DP<12>
J 0
(-2890 4410);
DISPLAY 0.659574 (-2890 4410);
PAINT MONO (-2890 4410);
DISPLAY INVISIBLE (-2890 4410);
FORCEPROP 1 LASTPIN (-2900 4400) BN 12
J 2
(-2848 4408);
DISPLAY 0.617021 (-2848 4408);
PAINT GREEN (-2848 4408);
FORCEPROP 2 LAST CDS_LIB mstr_standard
J 0
(-2850 4400);
PAINT MONO (-2850 4400);
DISPLAY INVISIBLE (-2850 4400);
FORCEPROP 1 LAST BODY_TYPE PLUMBING
J 2
(-2850 4350);
DISPLAY 1.595745 (-2850 4350);
PAINT GREEN (-2850 4350);
DISPLAY INVISIBLE (-2850 4350);
FORCEPROP 1 LAST HDL_TAP TRUE
J 2
(-3175 4275);
DISPLAY 1.595745 (-3175 4275);
PAINT GREEN (-3175 4275);
DISPLAY INVISIBLE (-3175 4275);
FORCEPROP 1 LAST PATH I167
J 2
(-2848 4400);
DISPLAY 0.872340 (-2848 4400);
PAINT GREEN (-2848 4400);
DISPLAY INVISIBLE (-2848 4400);
FORCEADD TAP..6
R 2
(-2850 4550);
FORCEPROP 3 LASTPIN (-2900 4550) SIG_NAME M_J_DQS_DP<15>
J 0
(-2890 4560);
DISPLAY 0.659574 (-2890 4560);
PAINT MONO (-2890 4560);
DISPLAY INVISIBLE (-2890 4560);
FORCEPROP 1 LASTPIN (-2900 4550) BN 15
J 2
(-2848 4558);
DISPLAY 0.617021 (-2848 4558);
PAINT GREEN (-2848 4558);
FORCEPROP 2 LAST CDS_LIB mstr_standard
J 0
(-2850 4550);
PAINT MONO (-2850 4550);
DISPLAY INVISIBLE (-2850 4550);
FORCEPROP 1 LAST BODY_TYPE PLUMBING
J 2
(-2850 4500);
DISPLAY 1.595745 (-2850 4500);
PAINT GREEN (-2850 4500);
DISPLAY INVISIBLE (-2850 4500);
FORCEPROP 1 LAST HDL_TAP TRUE
J 2
(-3175 4425);
DISPLAY 1.595745 (-3175 4425);
PAINT GREEN (-3175 4425);
DISPLAY INVISIBLE (-3175 4425);
FORCEPROP 1 LAST PATH I168
J 2
(-2848 4550);
DISPLAY 0.872340 (-2848 4550);
PAINT GREEN (-2848 4550);
DISPLAY INVISIBLE (-2848 4550);
FORCEADD TAP..6
R 2
(-2850 4600);
FORCEPROP 3 LASTPIN (-2900 4600) SIG_NAME M_J_DQS_DP<16>
J 0
(-2890 4610);
DISPLAY 0.659574 (-2890 4610);
PAINT MONO (-2890 4610);
DISPLAY INVISIBLE (-2890 4610);
FORCEPROP 1 LASTPIN (-2900 4600) BN 16
J 2
(-2848 4608);
DISPLAY 0.617021 (-2848 4608);
PAINT GREEN (-2848 4608);
FORCEPROP 2 LAST CDS_LIB mstr_standard
J 0
(-2850 4600);
PAINT MONO (-2850 4600);
DISPLAY INVISIBLE (-2850 4600);
FORCEPROP 1 LAST BODY_TYPE PLUMBING
J 2
(-2850 4550);
DISPLAY 1.595745 (-2850 4550);
PAINT GREEN (-2850 4550);
DISPLAY INVISIBLE (-2850 4550);
FORCEPROP 1 LAST HDL_TAP TRUE
J 2
(-3175 4475);
DISPLAY 1.595745 (-3175 4475);
PAINT GREEN (-3175 4475);
DISPLAY INVISIBLE (-3175 4475);
FORCEPROP 1 LAST PATH I169
J 2
(-2848 4600);
DISPLAY 0.872340 (-2848 4600);
PAINT GREEN (-2848 4600);
DISPLAY INVISIBLE (-2848 4600);
FORCEADD TAP..6
(-5575 1200);
FORCEPROP 3 LASTPIN (-5525 1200) SIG_NAME M_J_ECC<3>
J 0
(-5515 1210);
DISPLAY 0.659574 (-5515 1210);
PAINT MONO (-5515 1210);
DISPLAY INVISIBLE (-5515 1210);
FORCEPROP 1 LASTPIN (-5525 1200) BN 3
J 0
(-5577 1208);
DISPLAY 0.617021 (-5577 1208);
PAINT GREEN (-5577 1208);
FORCEPROP 2 LAST CDS_LIB mstr_standard
J 0
(-5575 1200);
PAINT MONO (-5575 1200);
DISPLAY INVISIBLE (-5575 1200);
FORCEPROP 1 LAST BODY_TYPE PLUMBING
J 0
(-5575 1150);
DISPLAY 1.595745 (-5575 1150);
PAINT GREEN (-5575 1150);
DISPLAY INVISIBLE (-5575 1150);
FORCEPROP 1 LAST HDL_TAP TRUE
J 0
(-5250 1075);
DISPLAY 1.595745 (-5250 1075);
PAINT GREEN (-5250 1075);
DISPLAY INVISIBLE (-5250 1075);
FORCEPROP 1 LAST PATH I17
J 0
(-5577 1200);
DISPLAY 0.872340 (-5577 1200);
PAINT GREEN (-5577 1200);
DISPLAY INVISIBLE (-5577 1200);
FORCEADD TAP..6
R 2
(-2850 4650);
FORCEPROP 3 LASTPIN (-2900 4650) SIG_NAME M_J_DQS_DP<17>
J 0
(-2890 4660);
DISPLAY 0.659574 (-2890 4660);
PAINT MONO (-2890 4660);
DISPLAY INVISIBLE (-2890 4660);
FORCEPROP 1 LASTPIN (-2900 4650) BN 17
J 2
(-2848 4658);
DISPLAY 0.617021 (-2848 4658);
PAINT GREEN (-2848 4658);
FORCEPROP 2 LAST CDS_LIB mstr_standard
J 2
(-2850 4650);
PAINT MONO (-2850 4650);
DISPLAY INVISIBLE (-2850 4650);
FORCEPROP 1 LAST BODY_TYPE PLUMBING
J 2
(-2850 4600);
DISPLAY 1.595745 (-2850 4600);
PAINT GREEN (-2850 4600);
DISPLAY INVISIBLE (-2850 4600);
FORCEPROP 1 LAST HDL_TAP TRUE
J 2
(-3175 4525);
DISPLAY 1.595745 (-3175 4525);
PAINT GREEN (-3175 4525);
DISPLAY INVISIBLE (-3175 4525);
FORCEPROP 1 LAST PATH I170
J 2
(-2848 4650);
DISPLAY 0.872340 (-2848 4650);
PAINT GREEN (-2848 4650);
DISPLAY INVISIBLE (-2848 4650);
FORCEADD OFFPAGE..3
(-2000 4725);
FORCEPROP 2 LAST $XR1 82 
J 0
(-1696 4725);
DISPLAY 0.638298 (-1696 4725);
PAINT MONO (-1696 4725);
FORCEPROP 2 LAST $XR0 81 
J 0
(-1786 4725);
DISPLAY 0.638298 (-1786 4725);
PAINT MONO (-1786 4725);
FORCEPROP 2 LAST CDS_LIB mstr_standard
J 0
(-2000 4725);
PAINT MONO (-2000 4725);
DISPLAY INVISIBLE (-2000 4725);
FORCEPROP 1 LAST OFFPAGE TRUE
J 0
(-1675 4600);
DISPLAY 1.170213 (-1675 4600);
PAINT GREEN (-1675 4600);
DISPLAY INVISIBLE (-1675 4600);
FORCEPROP 1 LAST COMMENT_BODY TRUE
J 0
(-2050 4625);
DISPLAY 1.170213 (-2050 4625);
PAINT GREEN (-2050 4625);
DISPLAY INVISIBLE (-2050 4625);
FORCEPROP 2 LAST PATH I171
J 0
(-1800 4800);
DISPLAY 1.021277 (-1800 4800);
PAINT ORANGE (-1800 4800);
DISPLAY INVISIBLE (-1800 4800);
FORCEADD SKX_EXT_B..5
(-4175 2550);
FORCEPROP 1 LAST LOCATION U2D1
J 0
(-4975 4900);
DISPLAY 0.617021 (-4975 4900);
PAINT AQUA (-4975 4900);
FORCEPROP 1 LAST PART_NUMBER TBD
J 0
(-4975 300);
DISPLAY 0.617021 (-4975 300);
PAINT BLUE (-4975 300);
FORCEPROP 1 LAST MATERIAL IC
J 0
(-4975 4850);
DISPLAY 0.617021 (-4975 4850);
PAINT SKYBLUE (-4975 4850);
FORCEPROP 2 LASTPIN (-3325 500) $PN V53
J 0
(-3315 510);
DISPLAY 0.617021 (-3315 510);
PAINT ORANGE (-3315 510);
FORCEPROP 2 LASTPIN (-3325 1550) $PN AB47
J 0
(-3315 1560);
DISPLAY 0.617021 (-3315 1560);
PAINT ORANGE (-3315 1560);
FORCEPROP 2 LASTPIN (-3325 1500) $PN V49
J 0
(-3315 1510);
DISPLAY 0.617021 (-3315 1510);
PAINT ORANGE (-3315 1510);
FORCEPROP 2 LASTPIN (-3325 1450) $PN AA48
J 0
(-3315 1460);
DISPLAY 0.617021 (-3315 1460);
PAINT ORANGE (-3315 1460);
FORCEPROP 2 LASTPIN (-3325 1400) $PN AA50
J 0
(-3315 1410);
DISPLAY 0.617021 (-3315 1410);
PAINT ORANGE (-3315 1410);
FORCEPROP 2 LASTPIN (-3325 2750) $PN AC46
J 0
(-3315 2760);
DISPLAY 0.617021 (-3315 2760);
PAINT ORANGE (-3315 2760);
FORCEPROP 2 LASTPIN (-3325 2700) $PN AA52
J 0
(-3315 2710);
DISPLAY 0.617021 (-3315 2710);
PAINT ORANGE (-3315 2710);
FORCEPROP 2 LASTPIN (-3325 2650) $PN AE54
J 0
(-3315 2660);
DISPLAY 0.617021 (-3315 2660);
PAINT ORANGE (-3315 2660);
FORCEPROP 2 LASTPIN (-3325 2600) $PN W50
J 0
(-3315 2610);
DISPLAY 0.617021 (-3315 2610);
PAINT ORANGE (-3315 2610);
FORCEPROP 2 LASTPIN (-3325 2550) $PN AD53
J 0
(-3315 2560);
DISPLAY 0.617021 (-3315 2560);
PAINT ORANGE (-3315 2560);
FORCEPROP 2 LASTPIN (-3325 2500) $PN AG62
J 0
(-3315 2510);
DISPLAY 0.617021 (-3315 2510);
PAINT ORANGE (-3315 2510);
FORCEPROP 2 LASTPIN (-3325 2450) $PN AG60
J 0
(-3315 2460);
DISPLAY 0.617021 (-3315 2460);
PAINT ORANGE (-3315 2460);
FORCEPROP 2 LASTPIN (-3325 2400) $PN AD55
J 0
(-3315 2410);
DISPLAY 0.617021 (-3315 2410);
PAINT ORANGE (-3315 2410);
FORCEPROP 2 LASTPIN (-3325 2350) $PN AG58
J 0
(-3315 2360);
DISPLAY 0.617021 (-3315 2360);
PAINT ORANGE (-3315 2360);
FORCEPROP 2 LASTPIN (-3325 2300) $PN AD59
J 0
(-3315 2310);
DISPLAY 0.617021 (-3315 2310);
PAINT ORANGE (-3315 2310);
FORCEPROP 2 LASTPIN (-3325 2250) $PN AE60
J 0
(-3315 2260);
DISPLAY 0.617021 (-3315 2260);
PAINT ORANGE (-3315 2260);
FORCEPROP 2 LASTPIN (-3325 2200) $PN AB59
J 0
(-3315 2210);
DISPLAY 0.617021 (-3315 2210);
PAINT ORANGE (-3315 2210);
FORCEPROP 2 LASTPIN (-3325 2150) $PN V59
J 0
(-3315 2160);
DISPLAY 0.617021 (-3315 2160);
PAINT ORANGE (-3315 2160);
FORCEPROP 2 LASTPIN (-3325 2100) $PN AA58
J 0
(-3315 2110);
DISPLAY 0.617021 (-3315 2110);
PAINT ORANGE (-3315 2110);
FORCEPROP 2 LASTPIN (-3325 2050) $PN W58
J 0
(-3315 2060);
DISPLAY 0.617021 (-3315 2060);
PAINT ORANGE (-3315 2060);
FORCEPROP 2 LASTPIN (-3325 2000) $PN AD57
J 0
(-3315 2010);
DISPLAY 0.617021 (-3315 2010);
PAINT ORANGE (-3315 2010);
FORCEPROP 2 LASTPIN (-3325 1950) $PN AE58
J 0
(-3315 1960);
DISPLAY 0.617021 (-3315 1960);
PAINT ORANGE (-3315 1960);
FORCEPROP 2 LASTPIN (-3325 1900) $PN AB53
J 0
(-3315 1910);
DISPLAY 0.617021 (-3315 1910);
PAINT ORANGE (-3315 1910);
FORCEPROP 2 LASTPIN (-5025 1400) $PN BA70
J 2
(-5035 1410);
DISPLAY 0.617021 (-5035 1410);
PAINT ORANGE (-5035 1410);
FORCEPROP 2 LASTPIN (-5025 1350) $PN AU70
J 2
(-5035 1360);
DISPLAY 0.617021 (-5035 1360);
PAINT ORANGE (-5035 1360);
FORCEPROP 2 LASTPIN (-5025 1300) $PN AY73
J 2
(-5035 1310);
DISPLAY 0.617021 (-5035 1310);
PAINT ORANGE (-5035 1310);
FORCEPROP 2 LASTPIN (-5025 1250) $PN AV73
J 2
(-5035 1260);
DISPLAY 0.617021 (-5035 1260);
PAINT ORANGE (-5035 1260);
FORCEPROP 2 LASTPIN (-5025 1200) $PN AY69
J 2
(-5035 1210);
DISPLAY 0.617021 (-5035 1210);
PAINT ORANGE (-5035 1210);
FORCEPROP 2 LASTPIN (-5025 1150) $PN AV69
J 2
(-5035 1160);
DISPLAY 0.617021 (-5035 1160);
PAINT ORANGE (-5035 1160);
FORCEPROP 2 LASTPIN (-5025 1050) $PN AU72
J 2
(-5035 1060);
DISPLAY 0.617021 (-5035 1060);
PAINT ORANGE (-5035 1060);
FORCEPROP 2 LASTPIN (-3325 4650) $PN AV71
J 0
(-3315 4660);
DISPLAY 0.617021 (-3315 4660);
PAINT ORANGE (-3315 4660);
FORCEPROP 2 LASTPIN (-3325 4600) $PN AE24
J 0
(-3315 4610);
DISPLAY 0.617021 (-3315 4610);
PAINT ORANGE (-3315 4610);
FORCEPROP 2 LASTPIN (-3325 4550) $PN AE30
J 0
(-3315 4560);
DISPLAY 0.617021 (-3315 4560);
PAINT ORANGE (-3315 4560);
FORCEPROP 2 LASTPIN (-3325 4500) $PN V33
J 0
(-3315 4510);
DISPLAY 0.617021 (-3315 4510);
PAINT ORANGE (-3315 4510);
FORCEPROP 2 LASTPIN (-3325 4450) $PN V39
J 0
(-3315 4460);
DISPLAY 0.617021 (-3315 4460);
PAINT ORANGE (-3315 4460);
FORCEPROP 2 LASTPIN (-3325 4400) $PN AN66
J 0
(-3315 4410);
DISPLAY 0.617021 (-3315 4410);
PAINT ORANGE (-3315 4410);
FORCEPROP 2 LASTPIN (-3325 4350) $PN V71
J 0
(-3315 4360);
DISPLAY 0.617021 (-3315 4360);
PAINT ORANGE (-3315 4360);
FORCEPROP 2 LASTPIN (-3325 4300) $PN AC76
J 0
(-3315 4310);
DISPLAY 0.617021 (-3315 4310);
PAINT ORANGE (-3315 4310);
FORCEPROP 2 LASTPIN (-3325 4250) $PN AN76
J 0
(-3315 4260);
DISPLAY 0.617021 (-3315 4260);
PAINT ORANGE (-3315 4260);
FORCEPROP 2 LASTPIN (-3325 4200) $PN AY71
J 0
(-3315 4210);
DISPLAY 0.617021 (-3315 4210);
PAINT ORANGE (-3315 4210);
FORCEPROP 2 LASTPIN (-3325 4150) $PN AG24
J 0
(-3315 4160);
DISPLAY 0.617021 (-3315 4160);
PAINT ORANGE (-3315 4160);
FORCEPROP 2 LASTPIN (-3325 4100) $PN AG30
J 0
(-3315 4110);
DISPLAY 0.617021 (-3315 4110);
PAINT ORANGE (-3315 4110);
FORCEPROP 2 LASTPIN (-3325 4050) $PN Y33
J 0
(-3315 4060);
DISPLAY 0.617021 (-3315 4060);
PAINT ORANGE (-3315 4060);
FORCEPROP 2 LASTPIN (-3325 4000) $PN Y39
J 0
(-3315 4010);
DISPLAY 0.617021 (-3315 4010);
PAINT ORANGE (-3315 4010);
FORCEPROP 2 LASTPIN (-3325 3950) $PN AR66
J 0
(-3315 3960);
DISPLAY 0.617021 (-3315 3960);
PAINT ORANGE (-3315 3960);
FORCEPROP 2 LASTPIN (-3325 3900) $PN W70
J 0
(-3315 3910);
DISPLAY 0.617021 (-3315 3910);
PAINT ORANGE (-3315 3910);
FORCEPROP 2 LASTPIN (-3325 3850) $PN AB75
J 0
(-3315 3860);
DISPLAY 0.617021 (-3315 3860);
PAINT ORANGE (-3315 3860);
FORCEPROP 2 LASTPIN (-3325 3800) $PN AM75
J 0
(-3315 3810);
DISPLAY 0.617021 (-3315 3810);
PAINT ORANGE (-3315 3810);
FORCEPROP 2 LASTPIN (-3325 3700) $PN AT71
J 0
(-3315 3710);
DISPLAY 0.617021 (-3315 3710);
PAINT ORANGE (-3315 3710);
FORCEPROP 2 LASTPIN (-3325 3650) $PN AC24
J 0
(-3315 3660);
DISPLAY 0.617021 (-3315 3660);
PAINT ORANGE (-3315 3660);
FORCEPROP 2 LASTPIN (-3325 3600) $PN AC30
J 0
(-3315 3610);
DISPLAY 0.617021 (-3315 3610);
PAINT ORANGE (-3315 3610);
FORCEPROP 2 LASTPIN (-3325 3550) $PN T33
J 0
(-3315 3560);
DISPLAY 0.617021 (-3315 3560);
PAINT ORANGE (-3315 3560);
FORCEPROP 2 LASTPIN (-3325 3500) $PN T39
J 0
(-3315 3510);
DISPLAY 0.617021 (-3315 3510);
PAINT ORANGE (-3315 3510);
FORCEPROP 2 LASTPIN (-3325 3450) $PN AL66
J 0
(-3315 3460);
DISPLAY 0.617021 (-3315 3460);
PAINT ORANGE (-3315 3460);
FORCEPROP 2 LASTPIN (-3325 3400) $PN U72
J 0
(-3315 3410);
DISPLAY 0.617021 (-3315 3410);
PAINT ORANGE (-3315 3410);
FORCEPROP 2 LASTPIN (-3325 3350) $PN AD77
J 0
(-3315 3360);
DISPLAY 0.617021 (-3315 3360);
PAINT ORANGE (-3315 3360);
FORCEPROP 2 LASTPIN (-3325 3300) $PN AP77
J 0
(-3315 3310);
DISPLAY 0.617021 (-3315 3310);
PAINT ORANGE (-3315 3310);
FORCEPROP 2 LASTPIN (-3325 3250) $PN BB71
J 0
(-3315 3260);
DISPLAY 0.617021 (-3315 3260);
PAINT ORANGE (-3315 3260);
FORCEPROP 2 LASTPIN (-3325 3200) $PN AJ24
J 0
(-3315 3210);
DISPLAY 0.617021 (-3315 3210);
PAINT ORANGE (-3315 3210);
FORCEPROP 2 LASTPIN (-3325 3150) $PN AJ30
J 0
(-3315 3160);
DISPLAY 0.617021 (-3315 3160);
PAINT ORANGE (-3315 3160);
FORCEPROP 2 LASTPIN (-3325 3100) $PN AB33
J 0
(-3315 3110);
DISPLAY 0.617021 (-3315 3110);
PAINT ORANGE (-3315 3110);
FORCEPROP 2 LASTPIN (-3325 3050) $PN AB39
J 0
(-3315 3060);
DISPLAY 0.617021 (-3315 3060);
PAINT ORANGE (-3315 3060);
FORCEPROP 2 LASTPIN (-3325 3000) $PN AU66
J 0
(-3315 3010);
DISPLAY 0.617021 (-3315 3010);
PAINT ORANGE (-3315 3010);
FORCEPROP 2 LASTPIN (-3325 2950) $PN Y69
J 0
(-3315 2960);
DISPLAY 0.617021 (-3315 2960);
PAINT ORANGE (-3315 2960);
FORCEPROP 2 LASTPIN (-3325 2900) $PN AA74
J 0
(-3315 2910);
DISPLAY 0.617021 (-3315 2910);
PAINT ORANGE (-3315 2910);
FORCEPROP 2 LASTPIN (-3325 2850) $PN AL74
J 0
(-3315 2860);
DISPLAY 0.617021 (-3315 2860);
PAINT ORANGE (-3315 2860);
FORCEPROP 2 LASTPIN (-5025 4650) $PN AH23
J 2
(-5035 4660);
DISPLAY 0.617021 (-5035 4660);
PAINT ORANGE (-5035 4660);
FORCEPROP 2 LASTPIN (-5025 4600) $PN AD23
J 2
(-5035 4610);
DISPLAY 0.617021 (-5035 4610);
PAINT ORANGE (-5035 4610);
FORCEPROP 2 LASTPIN (-5025 4550) $PN AG26
J 2
(-5035 4560);
DISPLAY 0.617021 (-5035 4560);
PAINT ORANGE (-5035 4560);
FORCEPROP 2 LASTPIN (-5025 4500) $PN AE26
J 2
(-5035 4510);
DISPLAY 0.617021 (-5035 4510);
PAINT ORANGE (-5035 4510);
FORCEPROP 2 LASTPIN (-5025 4450) $PN AG22
J 2
(-5035 4460);
DISPLAY 0.617021 (-5035 4460);
PAINT ORANGE (-5035 4460);
FORCEPROP 2 LASTPIN (-5025 4400) $PN AE22
J 2
(-5035 4410);
DISPLAY 0.617021 (-5035 4410);
PAINT ORANGE (-5035 4410);
FORCEPROP 2 LASTPIN (-5025 4350) $PN AH25
J 2
(-5035 4360);
DISPLAY 0.617021 (-5035 4360);
PAINT ORANGE (-5035 4360);
FORCEPROP 2 LASTPIN (-5025 4300) $PN AD25
J 2
(-5035 4310);
DISPLAY 0.617021 (-5035 4310);
PAINT ORANGE (-5035 4310);
FORCEPROP 2 LASTPIN (-5025 4250) $PN AH29
J 2
(-5035 4260);
DISPLAY 0.617021 (-5035 4260);
PAINT ORANGE (-5035 4260);
FORCEPROP 2 LASTPIN (-5025 4200) $PN AD29
J 2
(-5035 4210);
DISPLAY 0.617021 (-5035 4210);
PAINT ORANGE (-5035 4210);
FORCEPROP 2 LASTPIN (-5025 4150) $PN AG32
J 2
(-5035 4160);
DISPLAY 0.617021 (-5035 4160);
PAINT ORANGE (-5035 4160);
FORCEPROP 2 LASTPIN (-5025 4100) $PN AE32
J 2
(-5035 4110);
DISPLAY 0.617021 (-5035 4110);
PAINT ORANGE (-5035 4110);
FORCEPROP 2 LASTPIN (-5025 4050) $PN AG28
J 2
(-5035 4060);
DISPLAY 0.617021 (-5035 4060);
PAINT ORANGE (-5035 4060);
FORCEPROP 2 LASTPIN (-5025 4000) $PN AE28
J 2
(-5035 4010);
DISPLAY 0.617021 (-5035 4010);
PAINT ORANGE (-5035 4010);
FORCEPROP 2 LASTPIN (-5025 3950) $PN AH31
J 2
(-5035 3960);
DISPLAY 0.617021 (-5035 3960);
PAINT ORANGE (-5035 3960);
FORCEPROP 2 LASTPIN (-5025 3900) $PN AD31
J 2
(-5035 3910);
DISPLAY 0.617021 (-5035 3910);
PAINT ORANGE (-5035 3910);
FORCEPROP 2 LASTPIN (-5025 3850) $PN AA32
J 2
(-5035 3860);
DISPLAY 0.617021 (-5035 3860);
PAINT ORANGE (-5035 3860);
FORCEPROP 2 LASTPIN (-5025 3800) $PN U32
J 2
(-5035 3810);
DISPLAY 0.617021 (-5035 3810);
PAINT ORANGE (-5035 3810);
FORCEPROP 2 LASTPIN (-5025 3750) $PN Y35
J 2
(-5035 3760);
DISPLAY 0.617021 (-5035 3760);
PAINT ORANGE (-5035 3760);
FORCEPROP 2 LASTPIN (-5025 3700) $PN V35
J 2
(-5035 3710);
DISPLAY 0.617021 (-5035 3710);
PAINT ORANGE (-5035 3710);
FORCEPROP 2 LASTPIN (-5025 3650) $PN Y31
J 2
(-5035 3660);
DISPLAY 0.617021 (-5035 3660);
PAINT ORANGE (-5035 3660);
FORCEPROP 2 LASTPIN (-5025 3600) $PN V31
J 2
(-5035 3610);
DISPLAY 0.617021 (-5035 3610);
PAINT ORANGE (-5035 3610);
FORCEPROP 2 LASTPIN (-5025 3550) $PN AA34
J 2
(-5035 3560);
DISPLAY 0.617021 (-5035 3560);
PAINT ORANGE (-5035 3560);
FORCEPROP 2 LASTPIN (-5025 3500) $PN U34
J 2
(-5035 3510);
DISPLAY 0.617021 (-5035 3510);
PAINT ORANGE (-5035 3510);
FORCEPROP 2 LASTPIN (-5025 3450) $PN AA38
J 2
(-5035 3460);
DISPLAY 0.617021 (-5035 3460);
PAINT ORANGE (-5035 3460);
FORCEPROP 2 LASTPIN (-5025 3400) $PN U38
J 2
(-5035 3410);
DISPLAY 0.617021 (-5035 3410);
PAINT ORANGE (-5035 3410);
FORCEPROP 2 LASTPIN (-5025 3350) $PN Y41
J 2
(-5035 3360);
DISPLAY 0.617021 (-5035 3360);
PAINT ORANGE (-5035 3360);
FORCEPROP 2 LASTPIN (-5025 3300) $PN V41
J 2
(-5035 3310);
DISPLAY 0.617021 (-5035 3310);
PAINT ORANGE (-5035 3310);
FORCEPROP 2 LASTPIN (-5025 3250) $PN Y37
J 2
(-5035 3260);
DISPLAY 0.617021 (-5035 3260);
PAINT ORANGE (-5035 3260);
FORCEPROP 2 LASTPIN (-5025 3200) $PN V37
J 2
(-5035 3210);
DISPLAY 0.617021 (-5035 3210);
PAINT ORANGE (-5035 3210);
FORCEPROP 2 LASTPIN (-5025 3150) $PN AA40
J 2
(-5035 3160);
DISPLAY 0.617021 (-5035 3160);
PAINT ORANGE (-5035 3160);
FORCEPROP 2 LASTPIN (-5025 3100) $PN U40
J 2
(-5035 3110);
DISPLAY 0.617021 (-5035 3110);
PAINT ORANGE (-5035 3110);
FORCEPROP 2 LASTPIN (-5025 3050) $PN AT65
J 2
(-5035 3060);
DISPLAY 0.617021 (-5035 3060);
PAINT ORANGE (-5035 3060);
FORCEPROP 2 LASTPIN (-5025 3000) $PN AM65
J 2
(-5035 3010);
DISPLAY 0.617021 (-5035 3010);
PAINT ORANGE (-5035 3010);
FORCEPROP 2 LASTPIN (-5025 2850) $PN AR64
J 2
(-5035 2860);
DISPLAY 0.617021 (-5035 2860);
PAINT ORANGE (-5035 2860);
FORCEPROP 2 LASTPIN (-5025 2800) $PN AN64
J 2
(-5035 2810);
DISPLAY 0.617021 (-5035 2810);
PAINT ORANGE (-5035 2810);
FORCEPROP 2 LASTPIN (-5025 2750) $PN AT67
J 2
(-5035 2760);
DISPLAY 0.617021 (-5035 2760);
PAINT ORANGE (-5035 2760);
FORCEPROP 2 LASTPIN (-5025 2700) $PN AM67
J 2
(-5035 2710);
DISPLAY 0.617021 (-5035 2710);
PAINT ORANGE (-5035 2710);
FORCEPROP 2 LASTPIN (-5025 2650) $PN V69
J 2
(-5035 2660);
DISPLAY 0.617021 (-5035 2660);
PAINT ORANGE (-5035 2660);
FORCEPROP 2 LASTPIN (-5025 2600) $PN T71
J 2
(-5035 2610);
DISPLAY 0.617021 (-5035 2610);
PAINT ORANGE (-5035 2610);
FORCEPROP 2 LASTPIN (-5025 2550) $PN AB71
J 2
(-5035 2560);
DISPLAY 0.617021 (-5035 2560);
PAINT ORANGE (-5035 2560);
FORCEPROP 2 LASTPIN (-5025 2500) $PN AA72
J 2
(-5035 2510);
DISPLAY 0.617021 (-5035 2510);
PAINT ORANGE (-5035 2510);
FORCEPROP 2 LASTPIN (-5025 2450) $PN T69
J 2
(-5035 2460);
DISPLAY 0.617021 (-5035 2460);
PAINT ORANGE (-5035 2460);
FORCEPROP 2 LASTPIN (-5025 2400) $PN R70
J 2
(-5035 2410);
DISPLAY 0.617021 (-5035 2410);
PAINT ORANGE (-5035 2410);
FORCEPROP 2 LASTPIN (-5025 2350) $PN AA70
J 2
(-5035 2360);
DISPLAY 0.617021 (-5035 2360);
PAINT ORANGE (-5035 2360);
FORCEPROP 2 LASTPIN (-5025 2300) $PN W72
J 2
(-5035 2310);
DISPLAY 0.617021 (-5035 2310);
PAINT ORANGE (-5035 2310);
FORCEPROP 2 LASTPIN (-5025 2250) $PN Y75
J 2
(-5035 2260);
DISPLAY 0.617021 (-5035 2260);
PAINT ORANGE (-5035 2260);
FORCEPROP 2 LASTPIN (-5025 2200) $PN AB77
J 2
(-5035 2210);
DISPLAY 0.617021 (-5035 2210);
PAINT ORANGE (-5035 2210);
FORCEPROP 2 LASTPIN (-5025 2150) $PN AE74
J 2
(-5035 2160);
DISPLAY 0.617021 (-5035 2160);
PAINT ORANGE (-5035 2160);
FORCEPROP 2 LASTPIN (-5025 2100) $PN AF75
J 2
(-5035 2110);
DISPLAY 0.617021 (-5035 2110);
PAINT ORANGE (-5035 2110);
FORCEPROP 2 LASTPIN (-5025 2050) $PN W76
J 2
(-5035 2060);
DISPLAY 0.617021 (-5035 2060);
PAINT ORANGE (-5035 2060);
FORCEPROP 2 LASTPIN (-5025 2000) $PN Y77
J 2
(-5035 2010);
DISPLAY 0.617021 (-5035 2010);
PAINT ORANGE (-5035 2010);
FORCEPROP 2 LASTPIN (-5025 1950) $PN AC74
J 2
(-5035 1960);
DISPLAY 0.617021 (-5035 1960);
PAINT ORANGE (-5035 1960);
FORCEPROP 2 LASTPIN (-5025 1900) $PN AE76
J 2
(-5035 1910);
DISPLAY 0.617021 (-5035 1910);
PAINT ORANGE (-5035 1910);
FORCEPROP 2 LASTPIN (-5025 1850) $PN AK75
J 2
(-5035 1860);
DISPLAY 0.617021 (-5035 1860);
PAINT ORANGE (-5035 1860);
FORCEPROP 2 LASTPIN (-5025 1800) $PN AM77
J 2
(-5035 1810);
DISPLAY 0.617021 (-5035 1810);
PAINT ORANGE (-5035 1810);
FORCEPROP 2 LASTPIN (-5025 1750) $PN AR74
J 2
(-5035 1760);
DISPLAY 0.617021 (-5035 1760);
PAINT ORANGE (-5035 1760);
FORCEPROP 2 LASTPIN (-5025 1700) $PN AT75
J 2
(-5035 1710);
DISPLAY 0.617021 (-5035 1710);
PAINT ORANGE (-5035 1710);
FORCEPROP 2 LASTPIN (-5025 1650) $PN AJ76
J 2
(-5035 1660);
DISPLAY 0.617021 (-5035 1660);
PAINT ORANGE (-5035 1660);
FORCEPROP 2 LASTPIN (-5025 1600) $PN AK77
J 2
(-5035 1610);
DISPLAY 0.617021 (-5035 1610);
PAINT ORANGE (-5035 1610);
FORCEPROP 2 LASTPIN (-5025 1550) $PN AN74
J 2
(-5035 1560);
DISPLAY 0.617021 (-5035 1560);
PAINT ORANGE (-5035 1560);
FORCEPROP 2 LASTPIN (-5025 1500) $PN AR76
J 2
(-5035 1510);
DISPLAY 0.617021 (-5035 1510);
PAINT ORANGE (-5035 1510);
FORCEPROP 2 LASTPIN (-3325 1300) $PN V45
J 0
(-3315 1310);
DISPLAY 0.617021 (-3315 1310);
PAINT ORANGE (-3315 1310);
FORCEPROP 2 LASTPIN (-3325 1250) $PN T45
J 0
(-3315 1260);
DISPLAY 0.617021 (-3315 1260);
PAINT ORANGE (-3315 1260);
FORCEPROP 2 LASTPIN (-3325 1200) $PN W48
J 0
(-3315 1210);
DISPLAY 0.617021 (-3315 1210);
PAINT ORANGE (-3315 1210);
FORCEPROP 2 LASTPIN (-3325 1150) $PN AB51
J 0
(-3315 1160);
DISPLAY 0.617021 (-3315 1160);
PAINT ORANGE (-3315 1160);
FORCEPROP 2 LASTPIN (-3325 1100) $PN AA46
J 0
(-3315 1110);
DISPLAY 0.617021 (-3315 1110);
PAINT ORANGE (-3315 1110);
FORCEPROP 2 LASTPIN (-3325 1050) $PN W46
J 0
(-3315 1060);
DISPLAY 0.617021 (-3315 1060);
PAINT ORANGE (-3315 1060);
FORCEPROP 2 LASTPIN (-3325 1000) $PN AB49
J 0
(-3315 1010);
DISPLAY 0.617021 (-3315 1010);
PAINT ORANGE (-3315 1010);
FORCEPROP 2 LASTPIN (-3325 950) $PN V51
J 0
(-3315 960);
DISPLAY 0.617021 (-3315 960);
PAINT ORANGE (-3315 960);
FORCEPROP 2 LASTPIN (-5025 950) $PN V57
J 2
(-5035 960);
DISPLAY 0.617021 (-5035 960);
PAINT ORANGE (-5035 960);
FORCEPROP 2 LASTPIN (-5025 900) $PN AB57
J 2
(-5035 910);
DISPLAY 0.617021 (-5035 910);
PAINT ORANGE (-5035 910);
FORCEPROP 2 LASTPIN (-5025 850) $PN V55
J 2
(-5035 860);
DISPLAY 0.617021 (-5035 860);
PAINT ORANGE (-5035 860);
FORCEPROP 2 LASTPIN (-5025 800) $PN AB55
J 2
(-5035 810);
DISPLAY 0.617021 (-5035 810);
PAINT ORANGE (-5035 810);
FORCEPROP 2 LASTPIN (-5025 750) $PN W56
J 2
(-5035 760);
DISPLAY 0.617021 (-5035 760);
PAINT ORANGE (-5035 760);
FORCEPROP 2 LASTPIN (-5025 700) $PN AA56
J 2
(-5035 710);
DISPLAY 0.617021 (-5035 710);
PAINT ORANGE (-5035 710);
FORCEPROP 2 LASTPIN (-5025 650) $PN W54
J 2
(-5035 660);
DISPLAY 0.617021 (-5035 660);
PAINT ORANGE (-5035 660);
FORCEPROP 2 LASTPIN (-5025 600) $PN AA54
J 2
(-5035 610);
DISPLAY 0.617021 (-5035 610);
PAINT ORANGE (-5035 610);
FORCEPROP 2 LASTPIN (-3325 1800) $PN AB63
J 0
(-3315 1810);
DISPLAY 0.617021 (-3315 1810);
PAINT ORANGE (-3315 1810);
FORCEPROP 2 LASTPIN (-3325 1750) $PN V63
J 0
(-3315 1760);
DISPLAY 0.617021 (-3315 1760);
PAINT ORANGE (-3315 1760);
FORCEPROP 2 LASTPIN (-3325 1700) $PN AD63
J 0
(-3315 1710);
DISPLAY 0.617021 (-3315 1710);
PAINT ORANGE (-3315 1710);
FORCEPROP 2 LASTPIN (-3325 1650) $PN AA62
J 0
(-3315 1660);
DISPLAY 0.617021 (-3315 1660);
PAINT ORANGE (-3315 1660);
FORCEPROP 2 LASTPIN (-5025 500) $PN AB45
J 2
(-5035 510);
DISPLAY 0.617021 (-5035 510);
PAINT ORANGE (-5035 510);
FORCEPROP 2 LASTPIN (-3325 850) $PN AE62
J 0
(-3315 860);
DISPLAY 0.617021 (-3315 860);
PAINT ORANGE (-3315 860);
FORCEPROP 2 LASTPIN (-3325 800) $PN AA60
J 0
(-3315 810);
DISPLAY 0.617021 (-3315 810);
PAINT ORANGE (-3315 810);
FORCEPROP 2 LASTPIN (-3325 750) $PN AE56
J 0
(-3315 760);
DISPLAY 0.617021 (-3315 760);
PAINT ORANGE (-3315 760);
FORCEPROP 2 LASTPIN (-3325 700) $PN W52
J 0
(-3315 710);
DISPLAY 0.617021 (-3315 710);
PAINT ORANGE (-3315 710);
FORCEPROP 2 LASTPIN (-3325 550) $PN AD61
J 0
(-3315 560);
DISPLAY 0.617021 (-3315 560);
PAINT ORANGE (-3315 560);
FORCEPROP 2 LASTPIN (-3325 600) $PN AB61
J 0
(-3315 610);
DISPLAY 0.617021 (-3315 610);
PAINT ORANGE (-3315 610);
FORCEPROP 2 LASTPIN (-5025 2950) $PN AR68
J 2
(-5035 2960);
DISPLAY 0.617021 (-5035 2960);
PAINT ORANGE (-5035 2960);
FORCEPROP 2 LASTPIN (-5025 2900) $PN AN68
J 2
(-5035 2910);
DISPLAY 0.617021 (-5035 2910);
PAINT ORANGE (-5035 2910);
FORCEPROP 2 LASTPIN (-5025 1100) $PN BA72
J 2
(-5035 1110);
DISPLAY 0.617021 (-5035 1110);
PAINT ORANGE (-5035 1110);
FORCEPROP 1 LAST PACK_TYPE BGA1
J 0
(-4975 4950);
PAINT SKYBLUE (-4975 4950);
DISPLAY INVISIBLE (-4975 4950);
FORCEPROP 2 LAST SEC_TYPE BGA1
J 0
(-4975 4950);
DISPLAY 1.021277 (-4975 4950);
PAINT ORANGE (-4975 4950);
DISPLAY INVISIBLE (-4975 4950);
FORCEPROP 2 LAST CDS_LIB chpset_lib
J 0
(-4175 2550);
PAINT ORANGE (-4175 2550);
DISPLAY INVISIBLE (-4175 2550);
FORCEPROP 2 LAST SEC 5
J 0
(-4975 4950);
DISPLAY 0.680851 (-4975 4950);
PAINT MONO (-4975 4950);
DISPLAY INVISIBLE (-4975 4950);
FORCEPROP 2 LAST CDS_LOCATION U2D1
J 0
(-4975 4900);
DISPLAY 0.617021 (-4975 4900);
PAINT AQUA (-4975 4900);
DISPLAY INVISIBLE (-4975 4900);
FORCEPROP 1 LAST PATH I172
J 0
(-4175 4850);
PAINT GREEN (-4175 4850);
DISPLAY INVISIBLE (-4175 4850);
FORCEADD TAP..6
(-5575 1300);
FORCEPROP 3 LASTPIN (-5525 1300) SIG_NAME M_J_ECC<5>
J 0
(-5515 1310);
DISPLAY 0.659574 (-5515 1310);
PAINT MONO (-5515 1310);
DISPLAY INVISIBLE (-5515 1310);
FORCEPROP 1 LASTPIN (-5525 1300) BN 5
J 0
(-5577 1308);
DISPLAY 0.617021 (-5577 1308);
PAINT GREEN (-5577 1308);
FORCEPROP 2 LAST CDS_LIB mstr_standard
J 0
(-5575 1300);
PAINT MONO (-5575 1300);
DISPLAY INVISIBLE (-5575 1300);
FORCEPROP 1 LAST BODY_TYPE PLUMBING
J 0
(-5575 1250);
DISPLAY 1.595745 (-5575 1250);
PAINT GREEN (-5575 1250);
DISPLAY INVISIBLE (-5575 1250);
FORCEPROP 1 LAST HDL_TAP TRUE
J 0
(-5250 1175);
DISPLAY 1.595745 (-5250 1175);
PAINT GREEN (-5250 1175);
DISPLAY INVISIBLE (-5250 1175);
FORCEPROP 1 LAST PATH I18
J 0
(-5577 1300);
DISPLAY 0.872340 (-5577 1300);
PAINT GREEN (-5577 1300);
DISPLAY INVISIBLE (-5577 1300);
FORCEADD TAP..6
(-5575 1350);
FORCEPROP 3 LASTPIN (-5525 1350) SIG_NAME M_J_ECC<6>
J 0
(-5515 1360);
DISPLAY 0.659574 (-5515 1360);
PAINT MONO (-5515 1360);
DISPLAY INVISIBLE (-5515 1360);
FORCEPROP 1 LASTPIN (-5525 1350) BN 6
J 0
(-5577 1358);
DISPLAY 0.617021 (-5577 1358);
PAINT GREEN (-5577 1358);
FORCEPROP 2 LAST CDS_LIB mstr_standard
J 0
(-5575 1350);
PAINT MONO (-5575 1350);
DISPLAY INVISIBLE (-5575 1350);
FORCEPROP 1 LAST BODY_TYPE PLUMBING
J 0
(-5575 1300);
DISPLAY 1.595745 (-5575 1300);
PAINT GREEN (-5575 1300);
DISPLAY INVISIBLE (-5575 1300);
FORCEPROP 1 LAST HDL_TAP TRUE
J 0
(-5250 1225);
DISPLAY 1.595745 (-5250 1225);
PAINT GREEN (-5250 1225);
DISPLAY INVISIBLE (-5250 1225);
FORCEPROP 1 LAST PATH I19
J 0
(-5577 1350);
DISPLAY 0.872340 (-5577 1350);
PAINT GREEN (-5577 1350);
DISPLAY INVISIBLE (-5577 1350);
FORCEADD OFFPAGE..5
(-6425 800);
FORCEPROP 2 LAST $XR1 82 
J 0
(-6769 800);
DISPLAY 0.638298 (-6769 800);
PAINT MONO (-6769 800);
FORCEPROP 2 LAST $XR0 81 
J 0
(-6679 800);
DISPLAY 0.638298 (-6679 800);
PAINT MONO (-6679 800);
FORCEPROP 2 LAST CDS_LIB mstr_standard
J 0
(-6425 800);
PAINT MONO (-6425 800);
DISPLAY INVISIBLE (-6425 800);
FORCEPROP 1 LAST OFFPAGE TRUE
J 0
(-6100 675);
DISPLAY 1.170213 (-6100 675);
PAINT GREEN (-6100 675);
DISPLAY INVISIBLE (-6100 675);
FORCEPROP 1 LAST COMMENT_BODY TRUE
J 0
(-6325 725);
DISPLAY 1.170213 (-6325 725);
PAINT GREEN (-6325 725);
DISPLAY INVISIBLE (-6325 725);
FORCEPROP 2 LAST PATH I2
J 0
(-6375 875);
DISPLAY 1.021277 (-6375 875);
PAINT ORANGE (-6375 875);
DISPLAY INVISIBLE (-6375 875);
FORCEADD TAP..6
(-5575 1400);
FORCEPROP 3 LASTPIN (-5525 1400) SIG_NAME M_J_ECC<7>
J 0
(-5515 1410);
DISPLAY 0.659574 (-5515 1410);
PAINT MONO (-5515 1410);
DISPLAY INVISIBLE (-5515 1410);
FORCEPROP 1 LASTPIN (-5525 1400) BN 7
J 0
(-5577 1408);
DISPLAY 0.617021 (-5577 1408);
PAINT GREEN (-5577 1408);
FORCEPROP 2 LAST CDS_LIB mstr_standard
J 0
(-5575 1400);
PAINT MONO (-5575 1400);
DISPLAY INVISIBLE (-5575 1400);
FORCEPROP 1 LAST BODY_TYPE PLUMBING
J 0
(-5575 1350);
DISPLAY 1.595745 (-5575 1350);
PAINT GREEN (-5575 1350);
DISPLAY INVISIBLE (-5575 1350);
FORCEPROP 1 LAST HDL_TAP TRUE
J 0
(-5250 1275);
DISPLAY 1.595745 (-5250 1275);
PAINT GREEN (-5250 1275);
DISPLAY INVISIBLE (-5250 1275);
FORCEPROP 1 LAST PATH I20
J 0
(-5577 1400);
DISPLAY 0.872340 (-5577 1400);
PAINT GREEN (-5577 1400);
DISPLAY INVISIBLE (-5577 1400);
FORCEADD TAP..6
(-5575 1500);
FORCEPROP 3 LASTPIN (-5525 1500) SIG_NAME M_J_DQ<0>
J 0
(-5515 1510);
DISPLAY 0.659574 (-5515 1510);
PAINT MONO (-5515 1510);
DISPLAY INVISIBLE (-5515 1510);
FORCEPROP 1 LASTPIN (-5525 1500) BN 0
J 0
(-5577 1508);
DISPLAY 0.617021 (-5577 1508);
PAINT GREEN (-5577 1508);
FORCEPROP 2 LAST CDS_LIB mstr_standard
J 0
(-5575 1500);
PAINT MONO (-5575 1500);
DISPLAY INVISIBLE (-5575 1500);
FORCEPROP 1 LAST BODY_TYPE PLUMBING
J 0
(-5575 1450);
DISPLAY 1.595745 (-5575 1450);
PAINT GREEN (-5575 1450);
DISPLAY INVISIBLE (-5575 1450);
FORCEPROP 1 LAST HDL_TAP TRUE
J 0
(-5250 1375);
DISPLAY 1.595745 (-5250 1375);
PAINT GREEN (-5250 1375);
DISPLAY INVISIBLE (-5250 1375);
FORCEPROP 1 LAST PATH I21
J 0
(-5577 1500);
DISPLAY 0.872340 (-5577 1500);
PAINT GREEN (-5577 1500);
DISPLAY INVISIBLE (-5577 1500);
FORCEADD TAP..6
(-5575 1550);
FORCEPROP 3 LASTPIN (-5525 1550) SIG_NAME M_J_DQ<1>
J 0
(-5515 1560);
DISPLAY 0.659574 (-5515 1560);
PAINT MONO (-5515 1560);
DISPLAY INVISIBLE (-5515 1560);
FORCEPROP 1 LASTPIN (-5525 1550) BN 1
J 0
(-5577 1558);
DISPLAY 0.617021 (-5577 1558);
PAINT GREEN (-5577 1558);
FORCEPROP 2 LAST CDS_LIB mstr_standard
J 0
(-5575 1550);
PAINT MONO (-5575 1550);
DISPLAY INVISIBLE (-5575 1550);
FORCEPROP 1 LAST BODY_TYPE PLUMBING
J 0
(-5575 1500);
DISPLAY 1.595745 (-5575 1500);
PAINT GREEN (-5575 1500);
DISPLAY INVISIBLE (-5575 1500);
FORCEPROP 1 LAST HDL_TAP TRUE
J 0
(-5250 1425);
DISPLAY 1.595745 (-5250 1425);
PAINT GREEN (-5250 1425);
DISPLAY INVISIBLE (-5250 1425);
FORCEPROP 1 LAST PATH I22
J 0
(-5577 1550);
DISPLAY 0.872340 (-5577 1550);
PAINT GREEN (-5577 1550);
DISPLAY INVISIBLE (-5577 1550);
FORCEADD TAP..6
(-5575 1600);
FORCEPROP 3 LASTPIN (-5525 1600) SIG_NAME M_J_DQ<2>
J 0
(-5515 1610);
DISPLAY 0.659574 (-5515 1610);
PAINT MONO (-5515 1610);
DISPLAY INVISIBLE (-5515 1610);
FORCEPROP 1 LASTPIN (-5525 1600) BN 2
J 0
(-5577 1608);
DISPLAY 0.617021 (-5577 1608);
PAINT GREEN (-5577 1608);
FORCEPROP 2 LAST CDS_LIB mstr_standard
J 0
(-5575 1600);
PAINT MONO (-5575 1600);
DISPLAY INVISIBLE (-5575 1600);
FORCEPROP 1 LAST BODY_TYPE PLUMBING
J 0
(-5575 1550);
DISPLAY 1.595745 (-5575 1550);
PAINT GREEN (-5575 1550);
DISPLAY INVISIBLE (-5575 1550);
FORCEPROP 1 LAST HDL_TAP TRUE
J 0
(-5250 1475);
DISPLAY 1.595745 (-5250 1475);
PAINT GREEN (-5250 1475);
DISPLAY INVISIBLE (-5250 1475);
FORCEPROP 1 LAST PATH I23
J 0
(-5577 1600);
DISPLAY 0.872340 (-5577 1600);
PAINT GREEN (-5577 1600);
DISPLAY INVISIBLE (-5577 1600);
FORCEADD TAP..6
(-5575 1650);
FORCEPROP 3 LASTPIN (-5525 1650) SIG_NAME M_J_DQ<3>
J 0
(-5515 1660);
DISPLAY 0.659574 (-5515 1660);
PAINT MONO (-5515 1660);
DISPLAY INVISIBLE (-5515 1660);
FORCEPROP 1 LASTPIN (-5525 1650) BN 3
J 0
(-5577 1658);
DISPLAY 0.617021 (-5577 1658);
PAINT GREEN (-5577 1658);
FORCEPROP 2 LAST CDS_LIB mstr_standard
J 0
(-5575 1650);
PAINT MONO (-5575 1650);
DISPLAY INVISIBLE (-5575 1650);
FORCEPROP 1 LAST BODY_TYPE PLUMBING
J 0
(-5575 1600);
DISPLAY 1.595745 (-5575 1600);
PAINT GREEN (-5575 1600);
DISPLAY INVISIBLE (-5575 1600);
FORCEPROP 1 LAST HDL_TAP TRUE
J 0
(-5250 1525);
DISPLAY 1.595745 (-5250 1525);
PAINT GREEN (-5250 1525);
DISPLAY INVISIBLE (-5250 1525);
FORCEPROP 1 LAST PATH I24
J 0
(-5577 1650);
DISPLAY 0.872340 (-5577 1650);
PAINT GREEN (-5577 1650);
DISPLAY INVISIBLE (-5577 1650);
FORCEADD TAP..6
(-5575 1700);
FORCEPROP 3 LASTPIN (-5525 1700) SIG_NAME M_J_DQ<4>
J 0
(-5515 1710);
DISPLAY 0.659574 (-5515 1710);
PAINT MONO (-5515 1710);
DISPLAY INVISIBLE (-5515 1710);
FORCEPROP 1 LASTPIN (-5525 1700) BN 4
J 0
(-5577 1708);
DISPLAY 0.617021 (-5577 1708);
PAINT GREEN (-5577 1708);
FORCEPROP 2 LAST CDS_LIB mstr_standard
J 0
(-5575 1700);
PAINT MONO (-5575 1700);
DISPLAY INVISIBLE (-5575 1700);
FORCEPROP 1 LAST BODY_TYPE PLUMBING
J 0
(-5575 1650);
DISPLAY 1.595745 (-5575 1650);
PAINT GREEN (-5575 1650);
DISPLAY INVISIBLE (-5575 1650);
FORCEPROP 1 LAST HDL_TAP TRUE
J 0
(-5250 1575);
DISPLAY 1.595745 (-5250 1575);
PAINT GREEN (-5250 1575);
DISPLAY INVISIBLE (-5250 1575);
FORCEPROP 1 LAST PATH I25
J 0
(-5577 1700);
DISPLAY 0.872340 (-5577 1700);
PAINT GREEN (-5577 1700);
DISPLAY INVISIBLE (-5577 1700);
FORCEADD TAP..6
(-5575 1750);
FORCEPROP 3 LASTPIN (-5525 1750) SIG_NAME M_J_DQ<5>
J 0
(-5515 1760);
DISPLAY 0.659574 (-5515 1760);
PAINT MONO (-5515 1760);
DISPLAY INVISIBLE (-5515 1760);
FORCEPROP 1 LASTPIN (-5525 1750) BN 5
J 0
(-5577 1758);
DISPLAY 0.617021 (-5577 1758);
PAINT GREEN (-5577 1758);
FORCEPROP 2 LAST CDS_LIB mstr_standard
J 0
(-5575 1750);
PAINT MONO (-5575 1750);
DISPLAY INVISIBLE (-5575 1750);
FORCEPROP 1 LAST BODY_TYPE PLUMBING
J 0
(-5575 1700);
DISPLAY 1.595745 (-5575 1700);
PAINT GREEN (-5575 1700);
DISPLAY INVISIBLE (-5575 1700);
FORCEPROP 1 LAST HDL_TAP TRUE
J 0
(-5250 1625);
DISPLAY 1.595745 (-5250 1625);
PAINT GREEN (-5250 1625);
DISPLAY INVISIBLE (-5250 1625);
FORCEPROP 1 LAST PATH I26
J 0
(-5577 1750);
DISPLAY 0.872340 (-5577 1750);
PAINT GREEN (-5577 1750);
DISPLAY INVISIBLE (-5577 1750);
FORCEADD TAP..6
(-5575 1800);
FORCEPROP 3 LASTPIN (-5525 1800) SIG_NAME M_J_DQ<6>
J 0
(-5515 1810);
DISPLAY 0.659574 (-5515 1810);
PAINT MONO (-5515 1810);
DISPLAY INVISIBLE (-5515 1810);
FORCEPROP 1 LASTPIN (-5525 1800) BN 6
J 0
(-5577 1808);
DISPLAY 0.617021 (-5577 1808);
PAINT GREEN (-5577 1808);
FORCEPROP 2 LAST CDS_LIB mstr_standard
J 0
(-5575 1800);
PAINT MONO (-5575 1800);
DISPLAY INVISIBLE (-5575 1800);
FORCEPROP 1 LAST BODY_TYPE PLUMBING
J 0
(-5575 1750);
DISPLAY 1.595745 (-5575 1750);
PAINT GREEN (-5575 1750);
DISPLAY INVISIBLE (-5575 1750);
FORCEPROP 1 LAST HDL_TAP TRUE
J 0
(-5250 1675);
DISPLAY 1.595745 (-5250 1675);
PAINT GREEN (-5250 1675);
DISPLAY INVISIBLE (-5250 1675);
FORCEPROP 1 LAST PATH I27
J 0
(-5577 1800);
DISPLAY 0.872340 (-5577 1800);
PAINT GREEN (-5577 1800);
DISPLAY INVISIBLE (-5577 1800);
FORCEADD TAP..6
(-5575 1900);
FORCEPROP 3 LASTPIN (-5525 1900) SIG_NAME M_J_DQ<8>
J 0
(-5515 1910);
DISPLAY 0.659574 (-5515 1910);
PAINT MONO (-5515 1910);
DISPLAY INVISIBLE (-5515 1910);
FORCEPROP 1 LASTPIN (-5525 1900) BN 8
J 0
(-5577 1908);
DISPLAY 0.617021 (-5577 1908);
PAINT GREEN (-5577 1908);
FORCEPROP 2 LAST CDS_LIB mstr_standard
J 0
(-5575 1900);
PAINT MONO (-5575 1900);
DISPLAY INVISIBLE (-5575 1900);
FORCEPROP 1 LAST BODY_TYPE PLUMBING
J 0
(-5575 1850);
DISPLAY 1.595745 (-5575 1850);
PAINT GREEN (-5575 1850);
DISPLAY INVISIBLE (-5575 1850);
FORCEPROP 1 LAST HDL_TAP TRUE
J 0
(-5250 1775);
DISPLAY 1.595745 (-5250 1775);
PAINT GREEN (-5250 1775);
DISPLAY INVISIBLE (-5250 1775);
FORCEPROP 1 LAST PATH I28
J 0
(-5577 1900);
DISPLAY 0.872340 (-5577 1900);
PAINT GREEN (-5577 1900);
DISPLAY INVISIBLE (-5577 1900);
FORCEADD TAP..6
(-5575 1850);
FORCEPROP 3 LASTPIN (-5525 1850) SIG_NAME M_J_DQ<7>
J 0
(-5515 1860);
DISPLAY 0.659574 (-5515 1860);
PAINT MONO (-5515 1860);
DISPLAY INVISIBLE (-5515 1860);
FORCEPROP 1 LASTPIN (-5525 1850) BN 7
J 0
(-5577 1858);
DISPLAY 0.617021 (-5577 1858);
PAINT GREEN (-5577 1858);
FORCEPROP 2 LAST CDS_LIB mstr_standard
J 0
(-5575 1850);
PAINT MONO (-5575 1850);
DISPLAY INVISIBLE (-5575 1850);
FORCEPROP 1 LAST BODY_TYPE PLUMBING
J 0
(-5575 1800);
DISPLAY 1.595745 (-5575 1800);
PAINT GREEN (-5575 1800);
DISPLAY INVISIBLE (-5575 1800);
FORCEPROP 1 LAST HDL_TAP TRUE
J 0
(-5250 1725);
DISPLAY 1.595745 (-5250 1725);
PAINT GREEN (-5250 1725);
DISPLAY INVISIBLE (-5250 1725);
FORCEPROP 1 LAST PATH I29
J 0
(-5577 1850);
DISPLAY 0.872340 (-5577 1850);
PAINT GREEN (-5577 1850);
DISPLAY INVISIBLE (-5577 1850);
FORCEADD OFFPAGE..5
(-6425 1000);
FORCEPROP 2 LAST $XR1 82 
J 0
(-6769 1000);
DISPLAY 0.638298 (-6769 1000);
PAINT MONO (-6769 1000);
FORCEPROP 2 LAST $XR0 81 
J 0
(-6679 1000);
DISPLAY 0.638298 (-6679 1000);
PAINT MONO (-6679 1000);
FORCEPROP 2 LAST CDS_LIB mstr_standard
J 0
(-6425 1000);
PAINT MONO (-6425 1000);
DISPLAY INVISIBLE (-6425 1000);
FORCEPROP 1 LAST OFFPAGE TRUE
J 0
(-6100 875);
DISPLAY 1.170213 (-6100 875);
PAINT GREEN (-6100 875);
DISPLAY INVISIBLE (-6100 875);
FORCEPROP 1 LAST COMMENT_BODY TRUE
J 0
(-6325 925);
DISPLAY 1.170213 (-6325 925);
PAINT GREEN (-6325 925);
DISPLAY INVISIBLE (-6325 925);
FORCEPROP 2 LAST PATH I3
J 0
(-6375 1075);
DISPLAY 1.021277 (-6375 1075);
PAINT ORANGE (-6375 1075);
DISPLAY INVISIBLE (-6375 1075);
FORCEADD TAP..6
(-5575 1950);
FORCEPROP 3 LASTPIN (-5525 1950) SIG_NAME M_J_DQ<9>
J 0
(-5515 1960);
DISPLAY 0.659574 (-5515 1960);
PAINT MONO (-5515 1960);
DISPLAY INVISIBLE (-5515 1960);
FORCEPROP 1 LASTPIN (-5525 1950) BN 9
J 0
(-5577 1958);
DISPLAY 0.617021 (-5577 1958);
PAINT GREEN (-5577 1958);
FORCEPROP 2 LAST CDS_LIB mstr_standard
J 0
(-5575 1950);
PAINT MONO (-5575 1950);
DISPLAY INVISIBLE (-5575 1950);
FORCEPROP 1 LAST BODY_TYPE PLUMBING
J 0
(-5575 1900);
DISPLAY 1.595745 (-5575 1900);
PAINT GREEN (-5575 1900);
DISPLAY INVISIBLE (-5575 1900);
FORCEPROP 1 LAST HDL_TAP TRUE
J 0
(-5250 1825);
DISPLAY 1.595745 (-5250 1825);
PAINT GREEN (-5250 1825);
DISPLAY INVISIBLE (-5250 1825);
FORCEPROP 1 LAST PATH I31
J 0
(-5577 1950);
DISPLAY 0.872340 (-5577 1950);
PAINT GREEN (-5577 1950);
DISPLAY INVISIBLE (-5577 1950);
FORCEADD TAP..6
(-5575 2000);
FORCEPROP 3 LASTPIN (-5525 2000) SIG_NAME M_J_DQ<10>
J 0
(-5515 2010);
DISPLAY 0.659574 (-5515 2010);
PAINT MONO (-5515 2010);
DISPLAY INVISIBLE (-5515 2010);
FORCEPROP 1 LASTPIN (-5525 2000) BN 10
J 0
(-5577 2008);
DISPLAY 0.617021 (-5577 2008);
PAINT GREEN (-5577 2008);
FORCEPROP 2 LAST CDS_LIB mstr_standard
J 0
(-5575 2000);
PAINT MONO (-5575 2000);
DISPLAY INVISIBLE (-5575 2000);
FORCEPROP 1 LAST BODY_TYPE PLUMBING
J 0
(-5575 1950);
DISPLAY 1.595745 (-5575 1950);
PAINT GREEN (-5575 1950);
DISPLAY INVISIBLE (-5575 1950);
FORCEPROP 1 LAST HDL_TAP TRUE
J 0
(-5250 1875);
DISPLAY 1.595745 (-5250 1875);
PAINT GREEN (-5250 1875);
DISPLAY INVISIBLE (-5250 1875);
FORCEPROP 1 LAST PATH I32
J 0
(-5577 2000);
DISPLAY 0.872340 (-5577 2000);
PAINT GREEN (-5577 2000);
DISPLAY INVISIBLE (-5577 2000);
FORCEADD TAP..6
(-5575 2050);
FORCEPROP 3 LASTPIN (-5525 2050) SIG_NAME M_J_DQ<11>
J 0
(-5515 2060);
DISPLAY 0.659574 (-5515 2060);
PAINT MONO (-5515 2060);
DISPLAY INVISIBLE (-5515 2060);
FORCEPROP 1 LASTPIN (-5525 2050) BN 11
J 0
(-5577 2058);
DISPLAY 0.617021 (-5577 2058);
PAINT GREEN (-5577 2058);
FORCEPROP 2 LAST CDS_LIB mstr_standard
J 0
(-5575 2050);
PAINT MONO (-5575 2050);
DISPLAY INVISIBLE (-5575 2050);
FORCEPROP 1 LAST BODY_TYPE PLUMBING
J 0
(-5575 2000);
DISPLAY 1.595745 (-5575 2000);
PAINT GREEN (-5575 2000);
DISPLAY INVISIBLE (-5575 2000);
FORCEPROP 1 LAST HDL_TAP TRUE
J 0
(-5250 1925);
DISPLAY 1.595745 (-5250 1925);
PAINT GREEN (-5250 1925);
DISPLAY INVISIBLE (-5250 1925);
FORCEPROP 1 LAST PATH I33
J 0
(-5577 2050);
DISPLAY 0.872340 (-5577 2050);
PAINT GREEN (-5577 2050);
DISPLAY INVISIBLE (-5577 2050);
FORCEADD TAP..6
(-5575 2100);
FORCEPROP 3 LASTPIN (-5525 2100) SIG_NAME M_J_DQ<12>
J 0
(-5515 2110);
DISPLAY 0.659574 (-5515 2110);
PAINT MONO (-5515 2110);
DISPLAY INVISIBLE (-5515 2110);
FORCEPROP 1 LASTPIN (-5525 2100) BN 12
J 0
(-5577 2108);
DISPLAY 0.617021 (-5577 2108);
PAINT GREEN (-5577 2108);
FORCEPROP 2 LAST CDS_LIB mstr_standard
J 0
(-5575 2100);
PAINT MONO (-5575 2100);
DISPLAY INVISIBLE (-5575 2100);
FORCEPROP 1 LAST BODY_TYPE PLUMBING
J 0
(-5575 2050);
DISPLAY 1.595745 (-5575 2050);
PAINT GREEN (-5575 2050);
DISPLAY INVISIBLE (-5575 2050);
FORCEPROP 1 LAST HDL_TAP TRUE
J 0
(-5250 1975);
DISPLAY 1.595745 (-5250 1975);
PAINT GREEN (-5250 1975);
DISPLAY INVISIBLE (-5250 1975);
FORCEPROP 1 LAST PATH I34
J 0
(-5577 2100);
DISPLAY 0.872340 (-5577 2100);
PAINT GREEN (-5577 2100);
DISPLAY INVISIBLE (-5577 2100);
FORCEADD TAP..6
(-5575 2150);
FORCEPROP 3 LASTPIN (-5525 2150) SIG_NAME M_J_DQ<13>
J 0
(-5515 2160);
DISPLAY 0.659574 (-5515 2160);
PAINT MONO (-5515 2160);
DISPLAY INVISIBLE (-5515 2160);
FORCEPROP 1 LASTPIN (-5525 2150) BN 13
J 0
(-5577 2158);
DISPLAY 0.617021 (-5577 2158);
PAINT GREEN (-5577 2158);
FORCEPROP 2 LAST CDS_LIB mstr_standard
J 0
(-5575 2150);
PAINT MONO (-5575 2150);
DISPLAY INVISIBLE (-5575 2150);
FORCEPROP 1 LAST BODY_TYPE PLUMBING
J 0
(-5575 2100);
DISPLAY 1.595745 (-5575 2100);
PAINT GREEN (-5575 2100);
DISPLAY INVISIBLE (-5575 2100);
FORCEPROP 1 LAST HDL_TAP TRUE
J 0
(-5250 2025);
DISPLAY 1.595745 (-5250 2025);
PAINT GREEN (-5250 2025);
DISPLAY INVISIBLE (-5250 2025);
FORCEPROP 1 LAST PATH I35
J 0
(-5577 2150);
DISPLAY 0.872340 (-5577 2150);
PAINT GREEN (-5577 2150);
DISPLAY INVISIBLE (-5577 2150);
FORCEADD TAP..6
(-5575 2200);
FORCEPROP 3 LASTPIN (-5525 2200) SIG_NAME M_J_DQ<14>
J 0
(-5515 2210);
DISPLAY 0.659574 (-5515 2210);
PAINT MONO (-5515 2210);
DISPLAY INVISIBLE (-5515 2210);
FORCEPROP 1 LASTPIN (-5525 2200) BN 14
J 0
(-5577 2208);
DISPLAY 0.617021 (-5577 2208);
PAINT GREEN (-5577 2208);
FORCEPROP 2 LAST CDS_LIB mstr_standard
J 0
(-5575 2200);
PAINT MONO (-5575 2200);
DISPLAY INVISIBLE (-5575 2200);
FORCEPROP 1 LAST BODY_TYPE PLUMBING
J 0
(-5575 2150);
DISPLAY 1.595745 (-5575 2150);
PAINT GREEN (-5575 2150);
DISPLAY INVISIBLE (-5575 2150);
FORCEPROP 1 LAST HDL_TAP TRUE
J 0
(-5250 2075);
DISPLAY 1.595745 (-5250 2075);
PAINT GREEN (-5250 2075);
DISPLAY INVISIBLE (-5250 2075);
FORCEPROP 1 LAST PATH I36
J 0
(-5577 2200);
DISPLAY 0.872340 (-5577 2200);
PAINT GREEN (-5577 2200);
DISPLAY INVISIBLE (-5577 2200);
FORCEADD TAP..6
(-5575 2250);
FORCEPROP 3 LASTPIN (-5525 2250) SIG_NAME M_J_DQ<15>
J 0
(-5515 2260);
DISPLAY 0.659574 (-5515 2260);
PAINT MONO (-5515 2260);
DISPLAY INVISIBLE (-5515 2260);
FORCEPROP 1 LASTPIN (-5525 2250) BN 15
J 0
(-5577 2258);
DISPLAY 0.617021 (-5577 2258);
PAINT GREEN (-5577 2258);
FORCEPROP 2 LAST CDS_LIB mstr_standard
J 0
(-5575 2250);
PAINT MONO (-5575 2250);
DISPLAY INVISIBLE (-5575 2250);
FORCEPROP 1 LAST BODY_TYPE PLUMBING
J 0
(-5575 2200);
DISPLAY 1.595745 (-5575 2200);
PAINT GREEN (-5575 2200);
DISPLAY INVISIBLE (-5575 2200);
FORCEPROP 1 LAST HDL_TAP TRUE
J 0
(-5250 2125);
DISPLAY 1.595745 (-5250 2125);
PAINT GREEN (-5250 2125);
DISPLAY INVISIBLE (-5250 2125);
FORCEPROP 1 LAST PATH I37
J 0
(-5577 2250);
DISPLAY 0.872340 (-5577 2250);
PAINT GREEN (-5577 2250);
DISPLAY INVISIBLE (-5577 2250);
FORCEADD TAP..6
(-5575 2300);
FORCEPROP 3 LASTPIN (-5525 2300) SIG_NAME M_J_DQ<16>
J 0
(-5515 2310);
DISPLAY 0.659574 (-5515 2310);
PAINT MONO (-5515 2310);
DISPLAY INVISIBLE (-5515 2310);
FORCEPROP 1 LASTPIN (-5525 2300) BN 16
J 0
(-5577 2308);
DISPLAY 0.617021 (-5577 2308);
PAINT GREEN (-5577 2308);
FORCEPROP 2 LAST CDS_LIB mstr_standard
J 0
(-5575 2300);
PAINT MONO (-5575 2300);
DISPLAY INVISIBLE (-5575 2300);
FORCEPROP 1 LAST BODY_TYPE PLUMBING
J 0
(-5575 2250);
DISPLAY 1.595745 (-5575 2250);
PAINT GREEN (-5575 2250);
DISPLAY INVISIBLE (-5575 2250);
FORCEPROP 1 LAST HDL_TAP TRUE
J 0
(-5250 2175);
DISPLAY 1.595745 (-5250 2175);
PAINT GREEN (-5250 2175);
DISPLAY INVISIBLE (-5250 2175);
FORCEPROP 1 LAST PATH I38
J 0
(-5577 2300);
DISPLAY 0.872340 (-5577 2300);
PAINT GREEN (-5577 2300);
DISPLAY INVISIBLE (-5577 2300);
FORCEADD TAP..6
(-5575 2350);
FORCEPROP 3 LASTPIN (-5525 2350) SIG_NAME M_J_DQ<17>
J 0
(-5515 2360);
DISPLAY 0.659574 (-5515 2360);
PAINT MONO (-5515 2360);
DISPLAY INVISIBLE (-5515 2360);
FORCEPROP 1 LASTPIN (-5525 2350) BN 17
J 0
(-5577 2358);
DISPLAY 0.617021 (-5577 2358);
PAINT GREEN (-5577 2358);
FORCEPROP 2 LAST CDS_LIB mstr_standard
J 0
(-5575 2350);
PAINT MONO (-5575 2350);
DISPLAY INVISIBLE (-5575 2350);
FORCEPROP 1 LAST BODY_TYPE PLUMBING
J 0
(-5575 2300);
DISPLAY 1.595745 (-5575 2300);
PAINT GREEN (-5575 2300);
DISPLAY INVISIBLE (-5575 2300);
FORCEPROP 1 LAST HDL_TAP TRUE
J 0
(-5250 2225);
DISPLAY 1.595745 (-5250 2225);
PAINT GREEN (-5250 2225);
DISPLAY INVISIBLE (-5250 2225);
FORCEPROP 1 LAST PATH I39
J 0
(-5577 2350);
DISPLAY 0.872340 (-5577 2350);
PAINT GREEN (-5577 2350);
DISPLAY INVISIBLE (-5577 2350);
FORCEADD OFFPAGE..6
(-6425 1450);
FORCEPROP 2 LAST $XR1 82 
J 0
(-6764 1450);
DISPLAY 0.638298 (-6764 1450);
PAINT MONO (-6764 1450);
FORCEPROP 2 LAST $XR0 81 
J 0
(-6674 1450);
DISPLAY 0.638298 (-6674 1450);
PAINT MONO (-6674 1450);
FORCEPROP 2 LAST CDS_LIB mstr_standard
J 0
(-6425 1450);
PAINT MONO (-6425 1450);
DISPLAY INVISIBLE (-6425 1450);
FORCEPROP 1 LAST OFFPAGE TRUE
J 0
(-6100 1325);
DISPLAY 1.170213 (-6100 1325);
PAINT GREEN (-6100 1325);
DISPLAY INVISIBLE (-6100 1325);
FORCEPROP 1 LAST COMMENT_BODY TRUE
J 0
(-6325 1375);
DISPLAY 1.170213 (-6325 1375);
PAINT GREEN (-6325 1375);
DISPLAY INVISIBLE (-6325 1375);
FORCEPROP 2 LAST PATH I4
J 0
(-6375 1525);
DISPLAY 1.021277 (-6375 1525);
PAINT ORANGE (-6375 1525);
DISPLAY INVISIBLE (-6375 1525);
FORCEADD TAP..6
(-5575 2400);
FORCEPROP 3 LASTPIN (-5525 2400) SIG_NAME M_J_DQ<18>
J 0
(-5515 2410);
DISPLAY 0.659574 (-5515 2410);
PAINT MONO (-5515 2410);
DISPLAY INVISIBLE (-5515 2410);
FORCEPROP 1 LASTPIN (-5525 2400) BN 18
J 0
(-5577 2408);
DISPLAY 0.617021 (-5577 2408);
PAINT GREEN (-5577 2408);
FORCEPROP 2 LAST CDS_LIB mstr_standard
J 0
(-5575 2400);
PAINT MONO (-5575 2400);
DISPLAY INVISIBLE (-5575 2400);
FORCEPROP 1 LAST BODY_TYPE PLUMBING
J 0
(-5575 2350);
DISPLAY 1.595745 (-5575 2350);
PAINT GREEN (-5575 2350);
DISPLAY INVISIBLE (-5575 2350);
FORCEPROP 1 LAST HDL_TAP TRUE
J 0
(-5250 2275);
DISPLAY 1.595745 (-5250 2275);
PAINT GREEN (-5250 2275);
DISPLAY INVISIBLE (-5250 2275);
FORCEPROP 1 LAST PATH I40
J 0
(-5577 2400);
DISPLAY 0.872340 (-5577 2400);
PAINT GREEN (-5577 2400);
DISPLAY INVISIBLE (-5577 2400);
FORCEADD TAP..6
(-5575 2450);
FORCEPROP 3 LASTPIN (-5525 2450) SIG_NAME M_J_DQ<19>
J 0
(-5515 2460);
DISPLAY 0.659574 (-5515 2460);
PAINT MONO (-5515 2460);
DISPLAY INVISIBLE (-5515 2460);
FORCEPROP 1 LASTPIN (-5525 2450) BN 19
J 0
(-5577 2458);
DISPLAY 0.617021 (-5577 2458);
PAINT GREEN (-5577 2458);
FORCEPROP 2 LAST CDS_LIB mstr_standard
J 0
(-5575 2450);
PAINT MONO (-5575 2450);
DISPLAY INVISIBLE (-5575 2450);
FORCEPROP 1 LAST BODY_TYPE PLUMBING
J 0
(-5575 2400);
DISPLAY 1.595745 (-5575 2400);
PAINT GREEN (-5575 2400);
DISPLAY INVISIBLE (-5575 2400);
FORCEPROP 1 LAST HDL_TAP TRUE
J 0
(-5250 2325);
DISPLAY 1.595745 (-5250 2325);
PAINT GREEN (-5250 2325);
DISPLAY INVISIBLE (-5250 2325);
FORCEPROP 1 LAST PATH I41
J 0
(-5577 2450);
DISPLAY 0.872340 (-5577 2450);
PAINT GREEN (-5577 2450);
DISPLAY INVISIBLE (-5577 2450);
FORCEADD TAP..6
(-5575 2500);
FORCEPROP 3 LASTPIN (-5525 2500) SIG_NAME M_J_DQ<20>
J 0
(-5515 2510);
DISPLAY 0.659574 (-5515 2510);
PAINT MONO (-5515 2510);
DISPLAY INVISIBLE (-5515 2510);
FORCEPROP 1 LASTPIN (-5525 2500) BN 20
J 0
(-5577 2508);
DISPLAY 0.617021 (-5577 2508);
PAINT GREEN (-5577 2508);
FORCEPROP 2 LAST CDS_LIB mstr_standard
J 0
(-5575 2500);
PAINT MONO (-5575 2500);
DISPLAY INVISIBLE (-5575 2500);
FORCEPROP 1 LAST BODY_TYPE PLUMBING
J 0
(-5575 2450);
DISPLAY 1.595745 (-5575 2450);
PAINT GREEN (-5575 2450);
DISPLAY INVISIBLE (-5575 2450);
FORCEPROP 1 LAST HDL_TAP TRUE
J 0
(-5250 2375);
DISPLAY 1.595745 (-5250 2375);
PAINT GREEN (-5250 2375);
DISPLAY INVISIBLE (-5250 2375);
FORCEPROP 1 LAST PATH I42
J 0
(-5577 2500);
DISPLAY 0.872340 (-5577 2500);
PAINT GREEN (-5577 2500);
DISPLAY INVISIBLE (-5577 2500);
FORCEADD TAP..6
(-5575 2550);
FORCEPROP 3 LASTPIN (-5525 2550) SIG_NAME M_J_DQ<21>
J 0
(-5515 2560);
DISPLAY 0.659574 (-5515 2560);
PAINT MONO (-5515 2560);
DISPLAY INVISIBLE (-5515 2560);
FORCEPROP 1 LASTPIN (-5525 2550) BN 21
J 0
(-5577 2558);
DISPLAY 0.617021 (-5577 2558);
PAINT GREEN (-5577 2558);
FORCEPROP 2 LAST CDS_LIB mstr_standard
J 0
(-5575 2550);
PAINT MONO (-5575 2550);
DISPLAY INVISIBLE (-5575 2550);
FORCEPROP 1 LAST BODY_TYPE PLUMBING
J 0
(-5575 2500);
DISPLAY 1.595745 (-5575 2500);
PAINT GREEN (-5575 2500);
DISPLAY INVISIBLE (-5575 2500);
FORCEPROP 1 LAST HDL_TAP TRUE
J 0
(-5250 2425);
DISPLAY 1.595745 (-5250 2425);
PAINT GREEN (-5250 2425);
DISPLAY INVISIBLE (-5250 2425);
FORCEPROP 1 LAST PATH I43
J 0
(-5577 2550);
DISPLAY 0.872340 (-5577 2550);
PAINT GREEN (-5577 2550);
DISPLAY INVISIBLE (-5577 2550);
FORCEADD TAP..6
(-5575 2600);
FORCEPROP 3 LASTPIN (-5525 2600) SIG_NAME M_J_DQ<22>
J 0
(-5515 2610);
DISPLAY 0.659574 (-5515 2610);
PAINT MONO (-5515 2610);
DISPLAY INVISIBLE (-5515 2610);
FORCEPROP 1 LASTPIN (-5525 2600) BN 22
J 0
(-5577 2608);
DISPLAY 0.617021 (-5577 2608);
PAINT GREEN (-5577 2608);
FORCEPROP 2 LAST CDS_LIB mstr_standard
J 0
(-5575 2600);
PAINT MONO (-5575 2600);
DISPLAY INVISIBLE (-5575 2600);
FORCEPROP 1 LAST BODY_TYPE PLUMBING
J 0
(-5575 2550);
DISPLAY 1.595745 (-5575 2550);
PAINT GREEN (-5575 2550);
DISPLAY INVISIBLE (-5575 2550);
FORCEPROP 1 LAST HDL_TAP TRUE
J 0
(-5250 2475);
DISPLAY 1.595745 (-5250 2475);
PAINT GREEN (-5250 2475);
DISPLAY INVISIBLE (-5250 2475);
FORCEPROP 1 LAST PATH I44
J 0
(-5577 2600);
DISPLAY 0.872340 (-5577 2600);
PAINT GREEN (-5577 2600);
DISPLAY INVISIBLE (-5577 2600);
FORCEADD TAP..6
(-5575 2650);
FORCEPROP 3 LASTPIN (-5525 2650) SIG_NAME M_J_DQ<23>
J 0
(-5515 2660);
DISPLAY 0.659574 (-5515 2660);
PAINT MONO (-5515 2660);
DISPLAY INVISIBLE (-5515 2660);
FORCEPROP 1 LASTPIN (-5525 2650) BN 23
J 0
(-5577 2658);
DISPLAY 0.617021 (-5577 2658);
PAINT GREEN (-5577 2658);
FORCEPROP 2 LAST CDS_LIB mstr_standard
J 0
(-5575 2650);
PAINT MONO (-5575 2650);
DISPLAY INVISIBLE (-5575 2650);
FORCEPROP 1 LAST BODY_TYPE PLUMBING
J 0
(-5575 2600);
DISPLAY 1.595745 (-5575 2600);
PAINT GREEN (-5575 2600);
DISPLAY INVISIBLE (-5575 2600);
FORCEPROP 1 LAST HDL_TAP TRUE
J 0
(-5250 2525);
DISPLAY 1.595745 (-5250 2525);
PAINT GREEN (-5250 2525);
DISPLAY INVISIBLE (-5250 2525);
FORCEPROP 1 LAST PATH I45
J 0
(-5577 2650);
DISPLAY 0.872340 (-5577 2650);
PAINT GREEN (-5577 2650);
DISPLAY INVISIBLE (-5577 2650);
FORCEADD TAP..6
(-5575 2700);
FORCEPROP 3 LASTPIN (-5525 2700) SIG_NAME M_J_DQ<24>
J 0
(-5515 2710);
DISPLAY 0.659574 (-5515 2710);
PAINT MONO (-5515 2710);
DISPLAY INVISIBLE (-5515 2710);
FORCEPROP 1 LASTPIN (-5525 2700) BN 24
J 0
(-5577 2708);
DISPLAY 0.617021 (-5577 2708);
PAINT GREEN (-5577 2708);
FORCEPROP 2 LAST CDS_LIB mstr_standard
J 0
(-5575 2700);
PAINT MONO (-5575 2700);
DISPLAY INVISIBLE (-5575 2700);
FORCEPROP 1 LAST BODY_TYPE PLUMBING
J 0
(-5575 2650);
DISPLAY 1.595745 (-5575 2650);
PAINT GREEN (-5575 2650);
DISPLAY INVISIBLE (-5575 2650);
FORCEPROP 1 LAST HDL_TAP TRUE
J 0
(-5250 2575);
DISPLAY 1.595745 (-5250 2575);
PAINT GREEN (-5250 2575);
DISPLAY INVISIBLE (-5250 2575);
FORCEPROP 1 LAST PATH I46
J 0
(-5577 2700);
DISPLAY 0.872340 (-5577 2700);
PAINT GREEN (-5577 2700);
DISPLAY INVISIBLE (-5577 2700);
FORCEADD TAP..6
(-5575 2800);
FORCEPROP 3 LASTPIN (-5525 2800) SIG_NAME M_J_DQ<26>
J 0
(-5515 2810);
DISPLAY 0.659574 (-5515 2810);
PAINT MONO (-5515 2810);
DISPLAY INVISIBLE (-5515 2810);
FORCEPROP 1 LASTPIN (-5525 2800) BN 26
J 0
(-5577 2808);
DISPLAY 0.617021 (-5577 2808);
PAINT GREEN (-5577 2808);
FORCEPROP 2 LAST CDS_LIB mstr_standard
J 0
(-5575 2800);
PAINT MONO (-5575 2800);
DISPLAY INVISIBLE (-5575 2800);
FORCEPROP 1 LAST BODY_TYPE PLUMBING
J 0
(-5575 2750);
DISPLAY 1.595745 (-5575 2750);
PAINT GREEN (-5575 2750);
DISPLAY INVISIBLE (-5575 2750);
FORCEPROP 1 LAST HDL_TAP TRUE
J 0
(-5250 2675);
DISPLAY 1.595745 (-5250 2675);
PAINT GREEN (-5250 2675);
DISPLAY INVISIBLE (-5250 2675);
FORCEPROP 1 LAST PATH I47
J 0
(-5577 2800);
DISPLAY 0.872340 (-5577 2800);
PAINT GREEN (-5577 2800);
DISPLAY INVISIBLE (-5577 2800);
FORCEADD TAP..6
(-5575 2750);
FORCEPROP 3 LASTPIN (-5525 2750) SIG_NAME M_J_DQ<25>
J 0
(-5515 2760);
DISPLAY 0.659574 (-5515 2760);
PAINT MONO (-5515 2760);
DISPLAY INVISIBLE (-5515 2760);
FORCEPROP 1 LASTPIN (-5525 2750) BN 25
J 0
(-5577 2758);
DISPLAY 0.617021 (-5577 2758);
PAINT GREEN (-5577 2758);
FORCEPROP 2 LAST CDS_LIB mstr_standard
J 0
(-5575 2750);
PAINT MONO (-5575 2750);
DISPLAY INVISIBLE (-5575 2750);
FORCEPROP 1 LAST BODY_TYPE PLUMBING
J 0
(-5575 2700);
DISPLAY 1.595745 (-5575 2700);
PAINT GREEN (-5575 2700);
DISPLAY INVISIBLE (-5575 2700);
FORCEPROP 1 LAST HDL_TAP TRUE
J 0
(-5250 2625);
DISPLAY 1.595745 (-5250 2625);
PAINT GREEN (-5250 2625);
DISPLAY INVISIBLE (-5250 2625);
FORCEPROP 1 LAST PATH I48
J 0
(-5577 2750);
DISPLAY 0.872340 (-5577 2750);
PAINT GREEN (-5577 2750);
DISPLAY INVISIBLE (-5577 2750);
FORCEADD TAP..6
(-5575 2850);
FORCEPROP 3 LASTPIN (-5525 2850) SIG_NAME M_J_DQ<27>
J 0
(-5515 2860);
DISPLAY 0.659574 (-5515 2860);
PAINT MONO (-5515 2860);
DISPLAY INVISIBLE (-5515 2860);
FORCEPROP 1 LASTPIN (-5525 2850) BN 27
J 0
(-5577 2858);
DISPLAY 0.617021 (-5577 2858);
PAINT GREEN (-5577 2858);
FORCEPROP 2 LAST CDS_LIB mstr_standard
J 0
(-5575 2850);
PAINT MONO (-5575 2850);
DISPLAY INVISIBLE (-5575 2850);
FORCEPROP 1 LAST BODY_TYPE PLUMBING
J 0
(-5575 2800);
DISPLAY 1.595745 (-5575 2800);
PAINT GREEN (-5575 2800);
DISPLAY INVISIBLE (-5575 2800);
FORCEPROP 1 LAST HDL_TAP TRUE
J 0
(-5250 2725);
DISPLAY 1.595745 (-5250 2725);
PAINT GREEN (-5250 2725);
DISPLAY INVISIBLE (-5250 2725);
FORCEPROP 1 LAST PATH I49
J 0
(-5577 2850);
DISPLAY 0.872340 (-5577 2850);
PAINT GREEN (-5577 2850);
DISPLAY INVISIBLE (-5577 2850);
FORCEADD TAP..6
(-5575 600);
FORCEPROP 3 LASTPIN (-5525 600) SIG_NAME M_J_CLK_DN<0>
J 0
(-5515 610);
DISPLAY 0.659574 (-5515 610);
PAINT MONO (-5515 610);
DISPLAY INVISIBLE (-5515 610);
FORCEPROP 1 LASTPIN (-5525 600) BN 0
J 0
(-5577 608);
DISPLAY 0.617021 (-5577 608);
PAINT GREEN (-5577 608);
FORCEPROP 2 LAST CDS_LIB mstr_standard
J 0
(-5575 600);
PAINT MONO (-5575 600);
DISPLAY INVISIBLE (-5575 600);
FORCEPROP 1 LAST BODY_TYPE PLUMBING
J 0
(-5575 550);
DISPLAY 1.595745 (-5575 550);
PAINT GREEN (-5575 550);
DISPLAY INVISIBLE (-5575 550);
FORCEPROP 1 LAST HDL_TAP TRUE
J 0
(-5250 475);
DISPLAY 1.595745 (-5250 475);
PAINT GREEN (-5250 475);
DISPLAY INVISIBLE (-5250 475);
FORCEPROP 1 LAST PATH I5
J 0
(-5577 600);
DISPLAY 0.872340 (-5577 600);
PAINT GREEN (-5577 600);
DISPLAY INVISIBLE (-5577 600);
FORCEADD TAP..6
(-5575 2900);
FORCEPROP 3 LASTPIN (-5525 2900) SIG_NAME M_J_DQ<28>
J 0
(-5515 2910);
DISPLAY 0.659574 (-5515 2910);
PAINT MONO (-5515 2910);
DISPLAY INVISIBLE (-5515 2910);
FORCEPROP 1 LASTPIN (-5525 2900) BN 28
J 0
(-5577 2908);
DISPLAY 0.617021 (-5577 2908);
PAINT GREEN (-5577 2908);
FORCEPROP 2 LAST CDS_LIB mstr_standard
J 0
(-5575 2900);
PAINT MONO (-5575 2900);
DISPLAY INVISIBLE (-5575 2900);
FORCEPROP 1 LAST BODY_TYPE PLUMBING
J 0
(-5575 2850);
DISPLAY 1.595745 (-5575 2850);
PAINT GREEN (-5575 2850);
DISPLAY INVISIBLE (-5575 2850);
FORCEPROP 1 LAST HDL_TAP TRUE
J 0
(-5250 2775);
DISPLAY 1.595745 (-5250 2775);
PAINT GREEN (-5250 2775);
DISPLAY INVISIBLE (-5250 2775);
FORCEPROP 1 LAST PATH I50
J 0
(-5577 2900);
DISPLAY 0.872340 (-5577 2900);
PAINT GREEN (-5577 2900);
DISPLAY INVISIBLE (-5577 2900);
FORCEADD TAP..6
(-5575 2950);
FORCEPROP 3 LASTPIN (-5525 2950) SIG_NAME M_J_DQ<29>
J 0
(-5515 2960);
DISPLAY 0.659574 (-5515 2960);
PAINT MONO (-5515 2960);
DISPLAY INVISIBLE (-5515 2960);
FORCEPROP 1 LASTPIN (-5525 2950) BN 29
J 0
(-5577 2958);
DISPLAY 0.617021 (-5577 2958);
PAINT GREEN (-5577 2958);
FORCEPROP 2 LAST CDS_LIB mstr_standard
J 0
(-5575 2950);
PAINT MONO (-5575 2950);
DISPLAY INVISIBLE (-5575 2950);
FORCEPROP 1 LAST BODY_TYPE PLUMBING
J 0
(-5575 2900);
DISPLAY 1.595745 (-5575 2900);
PAINT GREEN (-5575 2900);
DISPLAY INVISIBLE (-5575 2900);
FORCEPROP 1 LAST HDL_TAP TRUE
J 0
(-5250 2825);
DISPLAY 1.595745 (-5250 2825);
PAINT GREEN (-5250 2825);
DISPLAY INVISIBLE (-5250 2825);
FORCEPROP 1 LAST PATH I51
J 0
(-5577 2950);
DISPLAY 0.872340 (-5577 2950);
PAINT GREEN (-5577 2950);
DISPLAY INVISIBLE (-5577 2950);
FORCEADD TAP..6
(-5575 3050);
FORCEPROP 3 LASTPIN (-5525 3050) SIG_NAME M_J_DQ<31>
J 0
(-5515 3060);
DISPLAY 0.659574 (-5515 3060);
PAINT MONO (-5515 3060);
DISPLAY INVISIBLE (-5515 3060);
FORCEPROP 1 LASTPIN (-5525 3050) BN 31
J 0
(-5577 3058);
DISPLAY 0.617021 (-5577 3058);
PAINT GREEN (-5577 3058);
FORCEPROP 2 LAST CDS_LIB mstr_standard
J 0
(-5575 3050);
PAINT MONO (-5575 3050);
DISPLAY INVISIBLE (-5575 3050);
FORCEPROP 1 LAST BODY_TYPE PLUMBING
J 0
(-5575 3000);
DISPLAY 1.595745 (-5575 3000);
PAINT GREEN (-5575 3000);
DISPLAY INVISIBLE (-5575 3000);
FORCEPROP 1 LAST HDL_TAP TRUE
J 0
(-5250 2925);
DISPLAY 1.595745 (-5250 2925);
PAINT GREEN (-5250 2925);
DISPLAY INVISIBLE (-5250 2925);
FORCEPROP 1 LAST PATH I52
J 0
(-5577 3050);
DISPLAY 0.872340 (-5577 3050);
PAINT GREEN (-5577 3050);
DISPLAY INVISIBLE (-5577 3050);
FORCEADD TAP..6
(-5575 3000);
FORCEPROP 3 LASTPIN (-5525 3000) SIG_NAME M_J_DQ<30>
J 0
(-5515 3010);
DISPLAY 0.659574 (-5515 3010);
PAINT MONO (-5515 3010);
DISPLAY INVISIBLE (-5515 3010);
FORCEPROP 1 LASTPIN (-5525 3000) BN 30
J 0
(-5577 3008);
DISPLAY 0.617021 (-5577 3008);
PAINT GREEN (-5577 3008);
FORCEPROP 2 LAST CDS_LIB mstr_standard
J 0
(-5575 3000);
PAINT MONO (-5575 3000);
DISPLAY INVISIBLE (-5575 3000);
FORCEPROP 1 LAST BODY_TYPE PLUMBING
J 0
(-5575 2950);
DISPLAY 1.595745 (-5575 2950);
PAINT GREEN (-5575 2950);
DISPLAY INVISIBLE (-5575 2950);
FORCEPROP 1 LAST HDL_TAP TRUE
J 0
(-5250 2875);
DISPLAY 1.595745 (-5250 2875);
PAINT GREEN (-5250 2875);
DISPLAY INVISIBLE (-5250 2875);
FORCEPROP 1 LAST PATH I53
J 0
(-5577 3000);
DISPLAY 0.872340 (-5577 3000);
PAINT GREEN (-5577 3000);
DISPLAY INVISIBLE (-5577 3000);
FORCEADD TAP..6
(-5575 3100);
FORCEPROP 3 LASTPIN (-5525 3100) SIG_NAME M_J_DQ<32>
J 0
(-5515 3110);
DISPLAY 0.659574 (-5515 3110);
PAINT MONO (-5515 3110);
DISPLAY INVISIBLE (-5515 3110);
FORCEPROP 1 LASTPIN (-5525 3100) BN 32
J 0
(-5577 3108);
DISPLAY 0.617021 (-5577 3108);
PAINT GREEN (-5577 3108);
FORCEPROP 2 LAST CDS_LIB mstr_standard
J 0
(-5575 3100);
PAINT MONO (-5575 3100);
DISPLAY INVISIBLE (-5575 3100);
FORCEPROP 1 LAST BODY_TYPE PLUMBING
J 0
(-5575 3050);
DISPLAY 1.595745 (-5575 3050);
PAINT GREEN (-5575 3050);
DISPLAY INVISIBLE (-5575 3050);
FORCEPROP 1 LAST HDL_TAP TRUE
J 0
(-5250 2975);
DISPLAY 1.595745 (-5250 2975);
PAINT GREEN (-5250 2975);
DISPLAY INVISIBLE (-5250 2975);
FORCEPROP 1 LAST PATH I54
J 0
(-5577 3100);
DISPLAY 0.872340 (-5577 3100);
PAINT GREEN (-5577 3100);
DISPLAY INVISIBLE (-5577 3100);
FORCEADD TAP..6
(-5575 3150);
FORCEPROP 3 LASTPIN (-5525 3150) SIG_NAME M_J_DQ<33>
J 0
(-5515 3160);
DISPLAY 0.659574 (-5515 3160);
PAINT MONO (-5515 3160);
DISPLAY INVISIBLE (-5515 3160);
FORCEPROP 1 LASTPIN (-5525 3150) BN 33
J 0
(-5577 3158);
DISPLAY 0.617021 (-5577 3158);
PAINT GREEN (-5577 3158);
FORCEPROP 2 LAST CDS_LIB mstr_standard
J 0
(-5575 3150);
PAINT MONO (-5575 3150);
DISPLAY INVISIBLE (-5575 3150);
FORCEPROP 1 LAST BODY_TYPE PLUMBING
J 0
(-5575 3100);
DISPLAY 1.595745 (-5575 3100);
PAINT GREEN (-5575 3100);
DISPLAY INVISIBLE (-5575 3100);
FORCEPROP 1 LAST HDL_TAP TRUE
J 0
(-5250 3025);
DISPLAY 1.595745 (-5250 3025);
PAINT GREEN (-5250 3025);
DISPLAY INVISIBLE (-5250 3025);
FORCEPROP 1 LAST PATH I55
J 0
(-5577 3150);
DISPLAY 0.872340 (-5577 3150);
PAINT GREEN (-5577 3150);
DISPLAY INVISIBLE (-5577 3150);
FORCEADD TAP..6
(-5575 3200);
FORCEPROP 3 LASTPIN (-5525 3200) SIG_NAME M_J_DQ<34>
J 0
(-5515 3210);
DISPLAY 0.659574 (-5515 3210);
PAINT MONO (-5515 3210);
DISPLAY INVISIBLE (-5515 3210);
FORCEPROP 1 LASTPIN (-5525 3200) BN 34
J 0
(-5577 3208);
DISPLAY 0.617021 (-5577 3208);
PAINT GREEN (-5577 3208);
FORCEPROP 2 LAST CDS_LIB mstr_standard
J 0
(-5575 3200);
PAINT MONO (-5575 3200);
DISPLAY INVISIBLE (-5575 3200);
FORCEPROP 1 LAST BODY_TYPE PLUMBING
J 0
(-5575 3150);
DISPLAY 1.595745 (-5575 3150);
PAINT GREEN (-5575 3150);
DISPLAY INVISIBLE (-5575 3150);
FORCEPROP 1 LAST HDL_TAP TRUE
J 0
(-5250 3075);
DISPLAY 1.595745 (-5250 3075);
PAINT GREEN (-5250 3075);
DISPLAY INVISIBLE (-5250 3075);
FORCEPROP 1 LAST PATH I56
J 0
(-5577 3200);
DISPLAY 0.872340 (-5577 3200);
PAINT GREEN (-5577 3200);
DISPLAY INVISIBLE (-5577 3200);
FORCEADD TAP..6
(-5575 3300);
FORCEPROP 3 LASTPIN (-5525 3300) SIG_NAME M_J_DQ<36>
J 0
(-5515 3310);
DISPLAY 0.659574 (-5515 3310);
PAINT MONO (-5515 3310);
DISPLAY INVISIBLE (-5515 3310);
FORCEPROP 1 LASTPIN (-5525 3300) BN 36
J 0
(-5577 3308);
DISPLAY 0.617021 (-5577 3308);
PAINT GREEN (-5577 3308);
FORCEPROP 2 LAST CDS_LIB mstr_standard
J 0
(-5575 3300);
PAINT MONO (-5575 3300);
DISPLAY INVISIBLE (-5575 3300);
FORCEPROP 1 LAST BODY_TYPE PLUMBING
J 0
(-5575 3250);
DISPLAY 1.595745 (-5575 3250);
PAINT GREEN (-5575 3250);
DISPLAY INVISIBLE (-5575 3250);
FORCEPROP 1 LAST HDL_TAP TRUE
J 0
(-5250 3175);
DISPLAY 1.595745 (-5250 3175);
PAINT GREEN (-5250 3175);
DISPLAY INVISIBLE (-5250 3175);
FORCEPROP 1 LAST PATH I57
J 0
(-5577 3300);
DISPLAY 0.872340 (-5577 3300);
PAINT GREEN (-5577 3300);
DISPLAY INVISIBLE (-5577 3300);
FORCEADD TAP..6
(-5575 3250);
FORCEPROP 3 LASTPIN (-5525 3250) SIG_NAME M_J_DQ<35>
J 0
(-5515 3260);
DISPLAY 0.659574 (-5515 3260);
PAINT MONO (-5515 3260);
DISPLAY INVISIBLE (-5515 3260);
FORCEPROP 1 LASTPIN (-5525 3250) BN 35
J 0
(-5577 3258);
DISPLAY 0.617021 (-5577 3258);
PAINT GREEN (-5577 3258);
FORCEPROP 2 LAST CDS_LIB mstr_standard
J 0
(-5575 3250);
PAINT MONO (-5575 3250);
DISPLAY INVISIBLE (-5575 3250);
FORCEPROP 1 LAST BODY_TYPE PLUMBING
J 0
(-5575 3200);
DISPLAY 1.595745 (-5575 3200);
PAINT GREEN (-5575 3200);
DISPLAY INVISIBLE (-5575 3200);
FORCEPROP 1 LAST HDL_TAP TRUE
J 0
(-5250 3125);
DISPLAY 1.595745 (-5250 3125);
PAINT GREEN (-5250 3125);
DISPLAY INVISIBLE (-5250 3125);
FORCEPROP 1 LAST PATH I58
J 0
(-5577 3250);
DISPLAY 0.872340 (-5577 3250);
PAINT GREEN (-5577 3250);
DISPLAY INVISIBLE (-5577 3250);
FORCEADD TAP..6
(-5575 3350);
FORCEPROP 3 LASTPIN (-5525 3350) SIG_NAME M_J_DQ<37>
J 0
(-5515 3360);
DISPLAY 0.659574 (-5515 3360);
PAINT MONO (-5515 3360);
DISPLAY INVISIBLE (-5515 3360);
FORCEPROP 1 LASTPIN (-5525 3350) BN 37
J 0
(-5577 3358);
DISPLAY 0.617021 (-5577 3358);
PAINT GREEN (-5577 3358);
FORCEPROP 2 LAST CDS_LIB mstr_standard
J 0
(-5575 3350);
PAINT MONO (-5575 3350);
DISPLAY INVISIBLE (-5575 3350);
FORCEPROP 1 LAST BODY_TYPE PLUMBING
J 0
(-5575 3300);
DISPLAY 1.595745 (-5575 3300);
PAINT GREEN (-5575 3300);
DISPLAY INVISIBLE (-5575 3300);
FORCEPROP 1 LAST HDL_TAP TRUE
J 0
(-5250 3225);
DISPLAY 1.595745 (-5250 3225);
PAINT GREEN (-5250 3225);
DISPLAY INVISIBLE (-5250 3225);
FORCEPROP 1 LAST PATH I59
J 0
(-5577 3350);
DISPLAY 0.872340 (-5577 3350);
PAINT GREEN (-5577 3350);
DISPLAY INVISIBLE (-5577 3350);
FORCEADD TAP..6
(-5575 650);
FORCEPROP 3 LASTPIN (-5525 650) SIG_NAME M_J_CLK_DN<1>
J 0
(-5515 660);
DISPLAY 0.659574 (-5515 660);
PAINT MONO (-5515 660);
DISPLAY INVISIBLE (-5515 660);
FORCEPROP 1 LASTPIN (-5525 650) BN 1
J 0
(-5577 658);
DISPLAY 0.617021 (-5577 658);
PAINT GREEN (-5577 658);
FORCEPROP 2 LAST CDS_LIB mstr_standard
J 0
(-5575 650);
PAINT MONO (-5575 650);
DISPLAY INVISIBLE (-5575 650);
FORCEPROP 1 LAST BODY_TYPE PLUMBING
J 0
(-5575 600);
DISPLAY 1.595745 (-5575 600);
PAINT GREEN (-5575 600);
DISPLAY INVISIBLE (-5575 600);
FORCEPROP 1 LAST HDL_TAP TRUE
J 0
(-5250 525);
DISPLAY 1.595745 (-5250 525);
PAINT GREEN (-5250 525);
DISPLAY INVISIBLE (-5250 525);
FORCEPROP 1 LAST PATH I6
J 0
(-5577 650);
DISPLAY 0.872340 (-5577 650);
PAINT GREEN (-5577 650);
DISPLAY INVISIBLE (-5577 650);
FORCEADD TAP..6
(-5575 3400);
FORCEPROP 3 LASTPIN (-5525 3400) SIG_NAME M_J_DQ<38>
J 0
(-5515 3410);
DISPLAY 0.659574 (-5515 3410);
PAINT MONO (-5515 3410);
DISPLAY INVISIBLE (-5515 3410);
FORCEPROP 1 LASTPIN (-5525 3400) BN 38
J 0
(-5577 3408);
DISPLAY 0.617021 (-5577 3408);
PAINT GREEN (-5577 3408);
FORCEPROP 2 LAST CDS_LIB mstr_standard
J 0
(-5575 3400);
PAINT MONO (-5575 3400);
DISPLAY INVISIBLE (-5575 3400);
FORCEPROP 1 LAST BODY_TYPE PLUMBING
J 0
(-5575 3350);
DISPLAY 1.595745 (-5575 3350);
PAINT GREEN (-5575 3350);
DISPLAY INVISIBLE (-5575 3350);
FORCEPROP 1 LAST HDL_TAP TRUE
J 0
(-5250 3275);
DISPLAY 1.595745 (-5250 3275);
PAINT GREEN (-5250 3275);
DISPLAY INVISIBLE (-5250 3275);
FORCEPROP 1 LAST PATH I60
J 0
(-5577 3400);
DISPLAY 0.872340 (-5577 3400);
PAINT GREEN (-5577 3400);
DISPLAY INVISIBLE (-5577 3400);
FORCEADD TAP..6
(-5575 3450);
FORCEPROP 3 LASTPIN (-5525 3450) SIG_NAME M_J_DQ<39>
J 0
(-5515 3460);
DISPLAY 0.659574 (-5515 3460);
PAINT MONO (-5515 3460);
DISPLAY INVISIBLE (-5515 3460);
FORCEPROP 1 LASTPIN (-5525 3450) BN 39
J 0
(-5577 3458);
DISPLAY 0.617021 (-5577 3458);
PAINT GREEN (-5577 3458);
FORCEPROP 2 LAST CDS_LIB mstr_standard
J 0
(-5575 3450);
PAINT MONO (-5575 3450);
DISPLAY INVISIBLE (-5575 3450);
FORCEPROP 1 LAST BODY_TYPE PLUMBING
J 0
(-5575 3400);
DISPLAY 1.595745 (-5575 3400);
PAINT GREEN (-5575 3400);
DISPLAY INVISIBLE (-5575 3400);
FORCEPROP 1 LAST HDL_TAP TRUE
J 0
(-5250 3325);
DISPLAY 1.595745 (-5250 3325);
PAINT GREEN (-5250 3325);
DISPLAY INVISIBLE (-5250 3325);
FORCEPROP 1 LAST PATH I61
J 0
(-5577 3450);
DISPLAY 0.872340 (-5577 3450);
PAINT GREEN (-5577 3450);
DISPLAY INVISIBLE (-5577 3450);
FORCEADD TAP..6
(-5575 3500);
FORCEPROP 3 LASTPIN (-5525 3500) SIG_NAME M_J_DQ<40>
J 0
(-5515 3510);
DISPLAY 0.659574 (-5515 3510);
PAINT MONO (-5515 3510);
DISPLAY INVISIBLE (-5515 3510);
FORCEPROP 1 LASTPIN (-5525 3500) BN 40
J 0
(-5577 3508);
DISPLAY 0.617021 (-5577 3508);
PAINT GREEN (-5577 3508);
FORCEPROP 2 LAST CDS_LIB mstr_standard
J 0
(-5575 3500);
PAINT MONO (-5575 3500);
DISPLAY INVISIBLE (-5575 3500);
FORCEPROP 1 LAST BODY_TYPE PLUMBING
J 0
(-5575 3450);
DISPLAY 1.595745 (-5575 3450);
PAINT GREEN (-5575 3450);
DISPLAY INVISIBLE (-5575 3450);
FORCEPROP 1 LAST HDL_TAP TRUE
J 0
(-5250 3375);
DISPLAY 1.595745 (-5250 3375);
PAINT GREEN (-5250 3375);
DISPLAY INVISIBLE (-5250 3375);
FORCEPROP 1 LAST PATH I62
J 0
(-5577 3500);
DISPLAY 0.872340 (-5577 3500);
PAINT GREEN (-5577 3500);
DISPLAY INVISIBLE (-5577 3500);
FORCEADD TAP..6
(-5575 3550);
FORCEPROP 3 LASTPIN (-5525 3550) SIG_NAME M_J_DQ<41>
J 0
(-5515 3560);
DISPLAY 0.659574 (-5515 3560);
PAINT MONO (-5515 3560);
DISPLAY INVISIBLE (-5515 3560);
FORCEPROP 1 LASTPIN (-5525 3550) BN 41
J 0
(-5577 3558);
DISPLAY 0.617021 (-5577 3558);
PAINT GREEN (-5577 3558);
FORCEPROP 2 LAST CDS_LIB mstr_standard
J 0
(-5575 3550);
PAINT MONO (-5575 3550);
DISPLAY INVISIBLE (-5575 3550);
FORCEPROP 1 LAST BODY_TYPE PLUMBING
J 0
(-5575 3500);
DISPLAY 1.595745 (-5575 3500);
PAINT GREEN (-5575 3500);
DISPLAY INVISIBLE (-5575 3500);
FORCEPROP 1 LAST HDL_TAP TRUE
J 0
(-5250 3425);
DISPLAY 1.595745 (-5250 3425);
PAINT GREEN (-5250 3425);
DISPLAY INVISIBLE (-5250 3425);
FORCEPROP 1 LAST PATH I63
J 0
(-5577 3550);
DISPLAY 0.872340 (-5577 3550);
PAINT GREEN (-5577 3550);
DISPLAY INVISIBLE (-5577 3550);
FORCEADD TAP..6
(-5575 3600);
FORCEPROP 3 LASTPIN (-5525 3600) SIG_NAME M_J_DQ<42>
J 0
(-5515 3610);
DISPLAY 0.659574 (-5515 3610);
PAINT MONO (-5515 3610);
DISPLAY INVISIBLE (-5515 3610);
FORCEPROP 1 LASTPIN (-5525 3600) BN 42
J 0
(-5577 3608);
DISPLAY 0.617021 (-5577 3608);
PAINT GREEN (-5577 3608);
FORCEPROP 2 LAST CDS_LIB mstr_standard
J 0
(-5575 3600);
PAINT MONO (-5575 3600);
DISPLAY INVISIBLE (-5575 3600);
FORCEPROP 1 LAST BODY_TYPE PLUMBING
J 0
(-5575 3550);
DISPLAY 1.595745 (-5575 3550);
PAINT GREEN (-5575 3550);
DISPLAY INVISIBLE (-5575 3550);
FORCEPROP 1 LAST HDL_TAP TRUE
J 0
(-5250 3475);
DISPLAY 1.595745 (-5250 3475);
PAINT GREEN (-5250 3475);
DISPLAY INVISIBLE (-5250 3475);
FORCEPROP 1 LAST PATH I64
J 0
(-5577 3600);
DISPLAY 0.872340 (-5577 3600);
PAINT GREEN (-5577 3600);
DISPLAY INVISIBLE (-5577 3600);
FORCEADD TAP..6
(-5575 3650);
FORCEPROP 3 LASTPIN (-5525 3650) SIG_NAME M_J_DQ<43>
J 0
(-5515 3660);
DISPLAY 0.659574 (-5515 3660);
PAINT MONO (-5515 3660);
DISPLAY INVISIBLE (-5515 3660);
FORCEPROP 1 LASTPIN (-5525 3650) BN 43
J 0
(-5577 3658);
DISPLAY 0.617021 (-5577 3658);
PAINT GREEN (-5577 3658);
FORCEPROP 2 LAST CDS_LIB mstr_standard
J 0
(-5575 3650);
PAINT MONO (-5575 3650);
DISPLAY INVISIBLE (-5575 3650);
FORCEPROP 1 LAST BODY_TYPE PLUMBING
J 0
(-5575 3600);
DISPLAY 1.595745 (-5575 3600);
PAINT GREEN (-5575 3600);
DISPLAY INVISIBLE (-5575 3600);
FORCEPROP 1 LAST HDL_TAP TRUE
J 0
(-5250 3525);
DISPLAY 1.595745 (-5250 3525);
PAINT GREEN (-5250 3525);
DISPLAY INVISIBLE (-5250 3525);
FORCEPROP 1 LAST PATH I65
J 0
(-5577 3650);
DISPLAY 0.872340 (-5577 3650);
PAINT GREEN (-5577 3650);
DISPLAY INVISIBLE (-5577 3650);
FORCEADD TAP..6
(-5575 3700);
FORCEPROP 3 LASTPIN (-5525 3700) SIG_NAME M_J_DQ<44>
J 0
(-5515 3710);
DISPLAY 0.659574 (-5515 3710);
PAINT MONO (-5515 3710);
DISPLAY INVISIBLE (-5515 3710);
FORCEPROP 1 LASTPIN (-5525 3700) BN 44
J 0
(-5577 3708);
DISPLAY 0.617021 (-5577 3708);
PAINT GREEN (-5577 3708);
FORCEPROP 2 LAST CDS_LIB mstr_standard
J 0
(-5575 3700);
PAINT MONO (-5575 3700);
DISPLAY INVISIBLE (-5575 3700);
FORCEPROP 1 LAST BODY_TYPE PLUMBING
J 0
(-5575 3650);
DISPLAY 1.595745 (-5575 3650);
PAINT GREEN (-5575 3650);
DISPLAY INVISIBLE (-5575 3650);
FORCEPROP 1 LAST HDL_TAP TRUE
J 0
(-5250 3575);
DISPLAY 1.595745 (-5250 3575);
PAINT GREEN (-5250 3575);
DISPLAY INVISIBLE (-5250 3575);
FORCEPROP 1 LAST PATH I66
J 0
(-5577 3700);
DISPLAY 0.872340 (-5577 3700);
PAINT GREEN (-5577 3700);
DISPLAY INVISIBLE (-5577 3700);
FORCEADD TAP..6
(-5575 3750);
FORCEPROP 3 LASTPIN (-5525 3750) SIG_NAME M_J_DQ<45>
J 0
(-5515 3760);
DISPLAY 0.659574 (-5515 3760);
PAINT MONO (-5515 3760);
DISPLAY INVISIBLE (-5515 3760);
FORCEPROP 1 LASTPIN (-5525 3750) BN 45
J 0
(-5577 3758);
DISPLAY 0.617021 (-5577 3758);
PAINT GREEN (-5577 3758);
FORCEPROP 2 LAST CDS_LIB mstr_standard
J 0
(-5575 3750);
PAINT MONO (-5575 3750);
DISPLAY INVISIBLE (-5575 3750);
FORCEPROP 1 LAST BODY_TYPE PLUMBING
J 0
(-5575 3700);
DISPLAY 1.595745 (-5575 3700);
PAINT GREEN (-5575 3700);
DISPLAY INVISIBLE (-5575 3700);
FORCEPROP 1 LAST HDL_TAP TRUE
J 0
(-5250 3625);
DISPLAY 1.595745 (-5250 3625);
PAINT GREEN (-5250 3625);
DISPLAY INVISIBLE (-5250 3625);
FORCEPROP 1 LAST PATH I67
J 0
(-5577 3750);
DISPLAY 0.872340 (-5577 3750);
PAINT GREEN (-5577 3750);
DISPLAY INVISIBLE (-5577 3750);
FORCEADD TAP..6
(-5575 3800);
FORCEPROP 3 LASTPIN (-5525 3800) SIG_NAME M_J_DQ<46>
J 0
(-5515 3810);
DISPLAY 0.659574 (-5515 3810);
PAINT MONO (-5515 3810);
DISPLAY INVISIBLE (-5515 3810);
FORCEPROP 1 LASTPIN (-5525 3800) BN 46
J 0
(-5577 3808);
DISPLAY 0.617021 (-5577 3808);
PAINT GREEN (-5577 3808);
FORCEPROP 2 LAST CDS_LIB mstr_standard
J 0
(-5575 3800);
PAINT MONO (-5575 3800);
DISPLAY INVISIBLE (-5575 3800);
FORCEPROP 1 LAST BODY_TYPE PLUMBING
J 0
(-5575 3750);
DISPLAY 1.595745 (-5575 3750);
PAINT GREEN (-5575 3750);
DISPLAY INVISIBLE (-5575 3750);
FORCEPROP 1 LAST HDL_TAP TRUE
J 0
(-5250 3675);
DISPLAY 1.595745 (-5250 3675);
PAINT GREEN (-5250 3675);
DISPLAY INVISIBLE (-5250 3675);
FORCEPROP 1 LAST PATH I68
J 0
(-5577 3800);
DISPLAY 0.872340 (-5577 3800);
PAINT GREEN (-5577 3800);
DISPLAY INVISIBLE (-5577 3800);
FORCEADD TAP..6
(-5575 3850);
FORCEPROP 3 LASTPIN (-5525 3850) SIG_NAME M_J_DQ<47>
J 0
(-5515 3860);
DISPLAY 0.659574 (-5515 3860);
PAINT MONO (-5515 3860);
DISPLAY INVISIBLE (-5515 3860);
FORCEPROP 1 LASTPIN (-5525 3850) BN 47
J 0
(-5577 3858);
DISPLAY 0.617021 (-5577 3858);
PAINT GREEN (-5577 3858);
FORCEPROP 2 LAST CDS_LIB mstr_standard
J 0
(-5575 3850);
PAINT MONO (-5575 3850);
DISPLAY INVISIBLE (-5575 3850);
FORCEPROP 1 LAST BODY_TYPE PLUMBING
J 0
(-5575 3800);
DISPLAY 1.595745 (-5575 3800);
PAINT GREEN (-5575 3800);
DISPLAY INVISIBLE (-5575 3800);
FORCEPROP 1 LAST HDL_TAP TRUE
J 0
(-5250 3725);
DISPLAY 1.595745 (-5250 3725);
PAINT GREEN (-5250 3725);
DISPLAY INVISIBLE (-5250 3725);
FORCEPROP 1 LAST PATH I69
J 0
(-5577 3850);
DISPLAY 0.872340 (-5577 3850);
PAINT GREEN (-5577 3850);
DISPLAY INVISIBLE (-5577 3850);
FORCEADD TAP..6
(-5575 750);
FORCEPROP 3 LASTPIN (-5525 750) SIG_NAME M_J_CLK_DN<3>
J 0
(-5515 760);
DISPLAY 0.659574 (-5515 760);
PAINT MONO (-5515 760);
DISPLAY INVISIBLE (-5515 760);
FORCEPROP 1 LASTPIN (-5525 750) BN 3
J 0
(-5577 758);
DISPLAY 0.617021 (-5577 758);
PAINT GREEN (-5577 758);
FORCEPROP 2 LAST CDS_LIB mstr_standard
J 0
(-5575 750);
PAINT MONO (-5575 750);
DISPLAY INVISIBLE (-5575 750);
FORCEPROP 1 LAST BODY_TYPE PLUMBING
J 0
(-5575 700);
DISPLAY 1.595745 (-5575 700);
PAINT GREEN (-5575 700);
DISPLAY INVISIBLE (-5575 700);
FORCEPROP 1 LAST HDL_TAP TRUE
J 0
(-5250 625);
DISPLAY 1.595745 (-5250 625);
PAINT GREEN (-5250 625);
DISPLAY INVISIBLE (-5250 625);
FORCEPROP 1 LAST PATH I7
J 0
(-5577 750);
DISPLAY 0.872340 (-5577 750);
PAINT GREEN (-5577 750);
DISPLAY INVISIBLE (-5577 750);
FORCEADD TAP..6
(-5575 3900);
FORCEPROP 3 LASTPIN (-5525 3900) SIG_NAME M_J_DQ<48>
J 0
(-5515 3910);
DISPLAY 0.659574 (-5515 3910);
PAINT MONO (-5515 3910);
DISPLAY INVISIBLE (-5515 3910);
FORCEPROP 1 LASTPIN (-5525 3900) BN 48
J 0
(-5577 3908);
DISPLAY 0.617021 (-5577 3908);
PAINT GREEN (-5577 3908);
FORCEPROP 2 LAST CDS_LIB mstr_standard
J 0
(-5575 3900);
PAINT MONO (-5575 3900);
DISPLAY INVISIBLE (-5575 3900);
FORCEPROP 1 LAST BODY_TYPE PLUMBING
J 0
(-5575 3850);
DISPLAY 1.595745 (-5575 3850);
PAINT GREEN (-5575 3850);
DISPLAY INVISIBLE (-5575 3850);
FORCEPROP 1 LAST HDL_TAP TRUE
J 0
(-5250 3775);
DISPLAY 1.595745 (-5250 3775);
PAINT GREEN (-5250 3775);
DISPLAY INVISIBLE (-5250 3775);
FORCEPROP 1 LAST PATH I70
J 0
(-5577 3900);
DISPLAY 0.872340 (-5577 3900);
PAINT GREEN (-5577 3900);
DISPLAY INVISIBLE (-5577 3900);
FORCEADD TAP..6
(-5575 3950);
FORCEPROP 3 LASTPIN (-5525 3950) SIG_NAME M_J_DQ<49>
J 0
(-5515 3960);
DISPLAY 0.659574 (-5515 3960);
PAINT MONO (-5515 3960);
DISPLAY INVISIBLE (-5515 3960);
FORCEPROP 1 LASTPIN (-5525 3950) BN 49
J 0
(-5577 3958);
DISPLAY 0.617021 (-5577 3958);
PAINT GREEN (-5577 3958);
FORCEPROP 2 LAST CDS_LIB mstr_standard
J 0
(-5575 3950);
PAINT MONO (-5575 3950);
DISPLAY INVISIBLE (-5575 3950);
FORCEPROP 1 LAST BODY_TYPE PLUMBING
J 0
(-5575 3900);
DISPLAY 1.595745 (-5575 3900);
PAINT GREEN (-5575 3900);
DISPLAY INVISIBLE (-5575 3900);
FORCEPROP 1 LAST HDL_TAP TRUE
J 0
(-5250 3825);
DISPLAY 1.595745 (-5250 3825);
PAINT GREEN (-5250 3825);
DISPLAY INVISIBLE (-5250 3825);
FORCEPROP 1 LAST PATH I71
J 0
(-5577 3950);
DISPLAY 0.872340 (-5577 3950);
PAINT GREEN (-5577 3950);
DISPLAY INVISIBLE (-5577 3950);
FORCEADD OFFPAGE..6
(-6425 4775);
FORCEPROP 2 LAST $XR1 82 
J 0
(-6764 4775);
DISPLAY 0.638298 (-6764 4775);
PAINT MONO (-6764 4775);
FORCEPROP 2 LAST $XR0 81 
J 0
(-6674 4775);
DISPLAY 0.638298 (-6674 4775);
PAINT MONO (-6674 4775);
FORCEPROP 2 LAST CDS_LIB mstr_standard
J 0
(-6425 4775);
PAINT MONO (-6425 4775);
DISPLAY INVISIBLE (-6425 4775);
FORCEPROP 1 LAST OFFPAGE TRUE
J 0
(-6100 4650);
DISPLAY 1.170213 (-6100 4650);
PAINT GREEN (-6100 4650);
DISPLAY INVISIBLE (-6100 4650);
FORCEPROP 1 LAST COMMENT_BODY TRUE
J 0
(-6325 4700);
DISPLAY 1.170213 (-6325 4700);
PAINT GREEN (-6325 4700);
DISPLAY INVISIBLE (-6325 4700);
FORCEPROP 2 LAST PATH I72
J 0
(-6375 4850);
DISPLAY 1.021277 (-6375 4850);
PAINT ORANGE (-6375 4850);
DISPLAY INVISIBLE (-6375 4850);
FORCEADD TAP..6
(-5575 4000);
FORCEPROP 3 LASTPIN (-5525 4000) SIG_NAME M_J_DQ<50>
J 0
(-5515 4010);
DISPLAY 0.659574 (-5515 4010);
PAINT MONO (-5515 4010);
DISPLAY INVISIBLE (-5515 4010);
FORCEPROP 1 LASTPIN (-5525 4000) BN 50
J 0
(-5577 4008);
DISPLAY 0.617021 (-5577 4008);
PAINT GREEN (-5577 4008);
FORCEPROP 2 LAST CDS_LIB mstr_standard
J 0
(-5575 4000);
PAINT MONO (-5575 4000);
DISPLAY INVISIBLE (-5575 4000);
FORCEPROP 1 LAST BODY_TYPE PLUMBING
J 0
(-5575 3950);
DISPLAY 1.595745 (-5575 3950);
PAINT GREEN (-5575 3950);
DISPLAY INVISIBLE (-5575 3950);
FORCEPROP 1 LAST HDL_TAP TRUE
J 0
(-5250 3875);
DISPLAY 1.595745 (-5250 3875);
PAINT GREEN (-5250 3875);
DISPLAY INVISIBLE (-5250 3875);
FORCEPROP 1 LAST PATH I73
J 0
(-5577 4000);
DISPLAY 0.872340 (-5577 4000);
PAINT GREEN (-5577 4000);
DISPLAY INVISIBLE (-5577 4000);
FORCEADD TAP..6
(-5575 4050);
FORCEPROP 3 LASTPIN (-5525 4050) SIG_NAME M_J_DQ<51>
J 0
(-5515 4060);
DISPLAY 0.659574 (-5515 4060);
PAINT MONO (-5515 4060);
DISPLAY INVISIBLE (-5515 4060);
FORCEPROP 1 LASTPIN (-5525 4050) BN 51
J 0
(-5577 4058);
DISPLAY 0.617021 (-5577 4058);
PAINT GREEN (-5577 4058);
FORCEPROP 2 LAST CDS_LIB mstr_standard
J 0
(-5575 4050);
PAINT MONO (-5575 4050);
DISPLAY INVISIBLE (-5575 4050);
FORCEPROP 1 LAST BODY_TYPE PLUMBING
J 0
(-5575 4000);
DISPLAY 1.595745 (-5575 4000);
PAINT GREEN (-5575 4000);
DISPLAY INVISIBLE (-5575 4000);
FORCEPROP 1 LAST HDL_TAP TRUE
J 0
(-5250 3925);
DISPLAY 1.595745 (-5250 3925);
PAINT GREEN (-5250 3925);
DISPLAY INVISIBLE (-5250 3925);
FORCEPROP 1 LAST PATH I74
J 0
(-5577 4050);
DISPLAY 0.872340 (-5577 4050);
PAINT GREEN (-5577 4050);
DISPLAY INVISIBLE (-5577 4050);
FORCEADD TAP..6
(-5575 4100);
FORCEPROP 3 LASTPIN (-5525 4100) SIG_NAME M_J_DQ<52>
J 0
(-5515 4110);
DISPLAY 0.659574 (-5515 4110);
PAINT MONO (-5515 4110);
DISPLAY INVISIBLE (-5515 4110);
FORCEPROP 1 LASTPIN (-5525 4100) BN 52
J 0
(-5577 4108);
DISPLAY 0.617021 (-5577 4108);
PAINT GREEN (-5577 4108);
FORCEPROP 2 LAST CDS_LIB mstr_standard
J 0
(-5575 4100);
PAINT MONO (-5575 4100);
DISPLAY INVISIBLE (-5575 4100);
FORCEPROP 1 LAST BODY_TYPE PLUMBING
J 0
(-5575 4050);
DISPLAY 1.595745 (-5575 4050);
PAINT GREEN (-5575 4050);
DISPLAY INVISIBLE (-5575 4050);
FORCEPROP 1 LAST HDL_TAP TRUE
J 0
(-5250 3975);
DISPLAY 1.595745 (-5250 3975);
PAINT GREEN (-5250 3975);
DISPLAY INVISIBLE (-5250 3975);
FORCEPROP 1 LAST PATH I75
J 0
(-5577 4100);
DISPLAY 0.872340 (-5577 4100);
PAINT GREEN (-5577 4100);
DISPLAY INVISIBLE (-5577 4100);
FORCEADD TAP..6
(-5575 4150);
FORCEPROP 3 LASTPIN (-5525 4150) SIG_NAME M_J_DQ<53>
J 0
(-5515 4160);
DISPLAY 0.659574 (-5515 4160);
PAINT MONO (-5515 4160);
DISPLAY INVISIBLE (-5515 4160);
FORCEPROP 1 LASTPIN (-5525 4150) BN 53
J 0
(-5577 4158);
DISPLAY 0.617021 (-5577 4158);
PAINT GREEN (-5577 4158);
FORCEPROP 2 LAST CDS_LIB mstr_standard
J 0
(-5575 4150);
PAINT MONO (-5575 4150);
DISPLAY INVISIBLE (-5575 4150);
FORCEPROP 1 LAST BODY_TYPE PLUMBING
J 0
(-5575 4100);
DISPLAY 1.595745 (-5575 4100);
PAINT GREEN (-5575 4100);
DISPLAY INVISIBLE (-5575 4100);
FORCEPROP 1 LAST HDL_TAP TRUE
J 0
(-5250 4025);
DISPLAY 1.595745 (-5250 4025);
PAINT GREEN (-5250 4025);
DISPLAY INVISIBLE (-5250 4025);
FORCEPROP 1 LAST PATH I76
J 0
(-5577 4150);
DISPLAY 0.872340 (-5577 4150);
PAINT GREEN (-5577 4150);
DISPLAY INVISIBLE (-5577 4150);
FORCEADD TAP..6
(-5575 4200);
FORCEPROP 3 LASTPIN (-5525 4200) SIG_NAME M_J_DQ<54>
J 0
(-5515 4210);
DISPLAY 0.659574 (-5515 4210);
PAINT MONO (-5515 4210);
DISPLAY INVISIBLE (-5515 4210);
FORCEPROP 1 LASTPIN (-5525 4200) BN 54
J 0
(-5577 4208);
DISPLAY 0.617021 (-5577 4208);
PAINT GREEN (-5577 4208);
FORCEPROP 2 LAST CDS_LIB mstr_standard
J 0
(-5575 4200);
PAINT MONO (-5575 4200);
DISPLAY INVISIBLE (-5575 4200);
FORCEPROP 1 LAST BODY_TYPE PLUMBING
J 0
(-5575 4150);
DISPLAY 1.595745 (-5575 4150);
PAINT GREEN (-5575 4150);
DISPLAY INVISIBLE (-5575 4150);
FORCEPROP 1 LAST HDL_TAP TRUE
J 0
(-5250 4075);
DISPLAY 1.595745 (-5250 4075);
PAINT GREEN (-5250 4075);
DISPLAY INVISIBLE (-5250 4075);
FORCEPROP 1 LAST PATH I77
J 0
(-5577 4200);
DISPLAY 0.872340 (-5577 4200);
PAINT GREEN (-5577 4200);
DISPLAY INVISIBLE (-5577 4200);
FORCEADD TAP..6
(-5575 4250);
FORCEPROP 3 LASTPIN (-5525 4250) SIG_NAME M_J_DQ<55>
J 0
(-5515 4260);
DISPLAY 0.659574 (-5515 4260);
PAINT MONO (-5515 4260);
DISPLAY INVISIBLE (-5515 4260);
FORCEPROP 1 LASTPIN (-5525 4250) BN 55
J 0
(-5577 4258);
DISPLAY 0.617021 (-5577 4258);
PAINT GREEN (-5577 4258);
FORCEPROP 2 LAST CDS_LIB mstr_standard
J 0
(-5575 4250);
PAINT MONO (-5575 4250);
DISPLAY INVISIBLE (-5575 4250);
FORCEPROP 1 LAST BODY_TYPE PLUMBING
J 0
(-5575 4200);
DISPLAY 1.595745 (-5575 4200);
PAINT GREEN (-5575 4200);
DISPLAY INVISIBLE (-5575 4200);
FORCEPROP 1 LAST HDL_TAP TRUE
J 0
(-5250 4125);
DISPLAY 1.595745 (-5250 4125);
PAINT GREEN (-5250 4125);
DISPLAY INVISIBLE (-5250 4125);
FORCEPROP 1 LAST PATH I78
J 0
(-5577 4250);
DISPLAY 0.872340 (-5577 4250);
PAINT GREEN (-5577 4250);
DISPLAY INVISIBLE (-5577 4250);
FORCEADD TAP..6
(-5575 4300);
FORCEPROP 3 LASTPIN (-5525 4300) SIG_NAME M_J_DQ<56>
J 0
(-5515 4310);
DISPLAY 0.659574 (-5515 4310);
PAINT MONO (-5515 4310);
DISPLAY INVISIBLE (-5515 4310);
FORCEPROP 1 LASTPIN (-5525 4300) BN 56
J 0
(-5577 4308);
DISPLAY 0.617021 (-5577 4308);
PAINT GREEN (-5577 4308);
FORCEPROP 2 LAST CDS_LIB mstr_standard
J 0
(-5575 4300);
PAINT MONO (-5575 4300);
DISPLAY INVISIBLE (-5575 4300);
FORCEPROP 1 LAST BODY_TYPE PLUMBING
J 0
(-5575 4250);
DISPLAY 1.595745 (-5575 4250);
PAINT GREEN (-5575 4250);
DISPLAY INVISIBLE (-5575 4250);
FORCEPROP 1 LAST HDL_TAP TRUE
J 0
(-5250 4175);
DISPLAY 1.595745 (-5250 4175);
PAINT GREEN (-5250 4175);
DISPLAY INVISIBLE (-5250 4175);
FORCEPROP 1 LAST PATH I79
J 0
(-5577 4300);
DISPLAY 0.872340 (-5577 4300);
PAINT GREEN (-5577 4300);
DISPLAY INVISIBLE (-5577 4300);
FORCEADD TAP..6
(-5575 700);
FORCEPROP 3 LASTPIN (-5525 700) SIG_NAME M_J_CLK_DN<2>
J 0
(-5515 710);
DISPLAY 0.659574 (-5515 710);
PAINT MONO (-5515 710);
DISPLAY INVISIBLE (-5515 710);
FORCEPROP 1 LASTPIN (-5525 700) BN 2
J 0
(-5577 708);
DISPLAY 0.617021 (-5577 708);
PAINT GREEN (-5577 708);
FORCEPROP 2 LAST CDS_LIB mstr_standard
J 0
(-5575 700);
PAINT MONO (-5575 700);
DISPLAY INVISIBLE (-5575 700);
FORCEPROP 1 LAST BODY_TYPE PLUMBING
J 0
(-5575 650);
DISPLAY 1.595745 (-5575 650);
PAINT GREEN (-5575 650);
DISPLAY INVISIBLE (-5575 650);
FORCEPROP 1 LAST HDL_TAP TRUE
J 0
(-5250 575);
DISPLAY 1.595745 (-5250 575);
PAINT GREEN (-5250 575);
DISPLAY INVISIBLE (-5250 575);
FORCEPROP 1 LAST PATH I8
J 0
(-5577 700);
DISPLAY 0.872340 (-5577 700);
PAINT GREEN (-5577 700);
DISPLAY INVISIBLE (-5577 700);
FORCEADD TAP..6
(-5575 4350);
FORCEPROP 3 LASTPIN (-5525 4350) SIG_NAME M_J_DQ<57>
J 0
(-5515 4360);
DISPLAY 0.659574 (-5515 4360);
PAINT MONO (-5515 4360);
DISPLAY INVISIBLE (-5515 4360);
FORCEPROP 1 LASTPIN (-5525 4350) BN 57
J 0
(-5577 4358);
DISPLAY 0.617021 (-5577 4358);
PAINT GREEN (-5577 4358);
FORCEPROP 2 LAST CDS_LIB mstr_standard
J 0
(-5575 4350);
PAINT MONO (-5575 4350);
DISPLAY INVISIBLE (-5575 4350);
FORCEPROP 1 LAST BODY_TYPE PLUMBING
J 0
(-5575 4300);
DISPLAY 1.595745 (-5575 4300);
PAINT GREEN (-5575 4300);
DISPLAY INVISIBLE (-5575 4300);
FORCEPROP 1 LAST HDL_TAP TRUE
J 0
(-5250 4225);
DISPLAY 1.595745 (-5250 4225);
PAINT GREEN (-5250 4225);
DISPLAY INVISIBLE (-5250 4225);
FORCEPROP 1 LAST PATH I80
J 0
(-5577 4350);
DISPLAY 0.872340 (-5577 4350);
PAINT GREEN (-5577 4350);
DISPLAY INVISIBLE (-5577 4350);
FORCEADD TAP..6
(-5575 4400);
FORCEPROP 3 LASTPIN (-5525 4400) SIG_NAME M_J_DQ<58>
J 0
(-5515 4410);
DISPLAY 0.659574 (-5515 4410);
PAINT MONO (-5515 4410);
DISPLAY INVISIBLE (-5515 4410);
FORCEPROP 1 LASTPIN (-5525 4400) BN 58
J 0
(-5577 4408);
DISPLAY 0.617021 (-5577 4408);
PAINT GREEN (-5577 4408);
FORCEPROP 2 LAST CDS_LIB mstr_standard
J 0
(-5575 4400);
PAINT MONO (-5575 4400);
DISPLAY INVISIBLE (-5575 4400);
FORCEPROP 1 LAST BODY_TYPE PLUMBING
J 0
(-5575 4350);
DISPLAY 1.595745 (-5575 4350);
PAINT GREEN (-5575 4350);
DISPLAY INVISIBLE (-5575 4350);
FORCEPROP 1 LAST HDL_TAP TRUE
J 0
(-5250 4275);
DISPLAY 1.595745 (-5250 4275);
PAINT GREEN (-5250 4275);
DISPLAY INVISIBLE (-5250 4275);
FORCEPROP 1 LAST PATH I81
J 0
(-5577 4400);
DISPLAY 0.872340 (-5577 4400);
PAINT GREEN (-5577 4400);
DISPLAY INVISIBLE (-5577 4400);
FORCEADD TAP..6
(-5575 4450);
FORCEPROP 3 LASTPIN (-5525 4450) SIG_NAME M_J_DQ<59>
J 0
(-5515 4460);
DISPLAY 0.659574 (-5515 4460);
PAINT MONO (-5515 4460);
DISPLAY INVISIBLE (-5515 4460);
FORCEPROP 1 LASTPIN (-5525 4450) BN 59
J 0
(-5577 4458);
DISPLAY 0.617021 (-5577 4458);
PAINT GREEN (-5577 4458);
FORCEPROP 2 LAST CDS_LIB mstr_standard
J 0
(-5575 4450);
PAINT MONO (-5575 4450);
DISPLAY INVISIBLE (-5575 4450);
FORCEPROP 1 LAST BODY_TYPE PLUMBING
J 0
(-5575 4400);
DISPLAY 1.595745 (-5575 4400);
PAINT GREEN (-5575 4400);
DISPLAY INVISIBLE (-5575 4400);
FORCEPROP 1 LAST HDL_TAP TRUE
J 0
(-5250 4325);
DISPLAY 1.595745 (-5250 4325);
PAINT GREEN (-5250 4325);
DISPLAY INVISIBLE (-5250 4325);
FORCEPROP 1 LAST PATH I82
J 0
(-5577 4450);
DISPLAY 0.872340 (-5577 4450);
PAINT GREEN (-5577 4450);
DISPLAY INVISIBLE (-5577 4450);
FORCEADD TAP..6
(-5575 4500);
FORCEPROP 3 LASTPIN (-5525 4500) SIG_NAME M_J_DQ<60>
J 0
(-5515 4510);
DISPLAY 0.659574 (-5515 4510);
PAINT MONO (-5515 4510);
DISPLAY INVISIBLE (-5515 4510);
FORCEPROP 1 LASTPIN (-5525 4500) BN 60
J 0
(-5577 4508);
DISPLAY 0.617021 (-5577 4508);
PAINT GREEN (-5577 4508);
FORCEPROP 2 LAST CDS_LIB mstr_standard
J 0
(-5575 4500);
PAINT MONO (-5575 4500);
DISPLAY INVISIBLE (-5575 4500);
FORCEPROP 1 LAST BODY_TYPE PLUMBING
J 0
(-5575 4450);
DISPLAY 1.595745 (-5575 4450);
PAINT GREEN (-5575 4450);
DISPLAY INVISIBLE (-5575 4450);
FORCEPROP 1 LAST HDL_TAP TRUE
J 0
(-5250 4375);
DISPLAY 1.595745 (-5250 4375);
PAINT GREEN (-5250 4375);
DISPLAY INVISIBLE (-5250 4375);
FORCEPROP 1 LAST PATH I83
J 0
(-5577 4500);
DISPLAY 0.872340 (-5577 4500);
PAINT GREEN (-5577 4500);
DISPLAY INVISIBLE (-5577 4500);
FORCEADD TAP..6
(-5575 4550);
FORCEPROP 3 LASTPIN (-5525 4550) SIG_NAME M_J_DQ<61>
J 0
(-5515 4560);
DISPLAY 0.659574 (-5515 4560);
PAINT MONO (-5515 4560);
DISPLAY INVISIBLE (-5515 4560);
FORCEPROP 1 LASTPIN (-5525 4550) BN 61
J 0
(-5577 4558);
DISPLAY 0.617021 (-5577 4558);
PAINT GREEN (-5577 4558);
FORCEPROP 2 LAST CDS_LIB mstr_standard
J 0
(-5575 4550);
PAINT MONO (-5575 4550);
DISPLAY INVISIBLE (-5575 4550);
FORCEPROP 1 LAST BODY_TYPE PLUMBING
J 0
(-5575 4500);
DISPLAY 1.595745 (-5575 4500);
PAINT GREEN (-5575 4500);
DISPLAY INVISIBLE (-5575 4500);
FORCEPROP 1 LAST HDL_TAP TRUE
J 0
(-5250 4425);
DISPLAY 1.595745 (-5250 4425);
PAINT GREEN (-5250 4425);
DISPLAY INVISIBLE (-5250 4425);
FORCEPROP 1 LAST PATH I84
J 0
(-5577 4550);
DISPLAY 0.872340 (-5577 4550);
PAINT GREEN (-5577 4550);
DISPLAY INVISIBLE (-5577 4550);
FORCEADD TAP..6
(-5575 4600);
FORCEPROP 3 LASTPIN (-5525 4600) SIG_NAME M_J_DQ<62>
J 0
(-5515 4610);
DISPLAY 0.659574 (-5515 4610);
PAINT MONO (-5515 4610);
DISPLAY INVISIBLE (-5515 4610);
FORCEPROP 1 LASTPIN (-5525 4600) BN 62
J 0
(-5577 4608);
DISPLAY 0.617021 (-5577 4608);
PAINT GREEN (-5577 4608);
FORCEPROP 2 LAST CDS_LIB mstr_standard
J 0
(-5575 4600);
PAINT MONO (-5575 4600);
DISPLAY INVISIBLE (-5575 4600);
FORCEPROP 1 LAST BODY_TYPE PLUMBING
J 0
(-5575 4550);
DISPLAY 1.595745 (-5575 4550);
PAINT GREEN (-5575 4550);
DISPLAY INVISIBLE (-5575 4550);
FORCEPROP 1 LAST HDL_TAP TRUE
J 0
(-5250 4475);
DISPLAY 1.595745 (-5250 4475);
PAINT GREEN (-5250 4475);
DISPLAY INVISIBLE (-5250 4475);
FORCEPROP 1 LAST PATH I85
J 0
(-5577 4600);
DISPLAY 0.872340 (-5577 4600);
PAINT GREEN (-5577 4600);
DISPLAY INVISIBLE (-5577 4600);
FORCEADD TAP..6
(-5575 4650);
FORCEPROP 3 LASTPIN (-5525 4650) SIG_NAME M_J_DQ<63>
J 0
(-5515 4660);
DISPLAY 0.659574 (-5515 4660);
PAINT MONO (-5515 4660);
DISPLAY INVISIBLE (-5515 4660);
FORCEPROP 1 LASTPIN (-5525 4650) BN 63
J 0
(-5577 4658);
DISPLAY 0.617021 (-5577 4658);
PAINT GREEN (-5577 4658);
FORCEPROP 2 LAST CDS_LIB mstr_standard
J 0
(-5575 4650);
PAINT MONO (-5575 4650);
DISPLAY INVISIBLE (-5575 4650);
FORCEPROP 1 LAST BODY_TYPE PLUMBING
J 0
(-5575 4600);
DISPLAY 1.595745 (-5575 4600);
PAINT GREEN (-5575 4600);
DISPLAY INVISIBLE (-5575 4600);
FORCEPROP 1 LAST HDL_TAP TRUE
J 0
(-5250 4525);
DISPLAY 1.595745 (-5250 4525);
PAINT GREEN (-5250 4525);
DISPLAY INVISIBLE (-5250 4525);
FORCEPROP 1 LAST PATH I86
J 0
(-5577 4650);
DISPLAY 0.872340 (-5577 4650);
PAINT GREEN (-5577 4650);
DISPLAY INVISIBLE (-5577 4650);
FORCEADD TAP..6
R 2
(-2850 750);
FORCEPROP 3 LASTPIN (-2900 750) SIG_NAME M_J_BA<1>
J 0
(-2890 760);
DISPLAY 0.659574 (-2890 760);
PAINT MONO (-2890 760);
DISPLAY INVISIBLE (-2890 760);
FORCEPROP 1 LASTPIN (-2900 750) BN 1
J 2
(-2848 758);
DISPLAY 0.617021 (-2848 758);
PAINT GREEN (-2848 758);
FORCEPROP 2 LAST CDS_LIB mstr_standard
J 0
(-2850 750);
PAINT MONO (-2850 750);
DISPLAY INVISIBLE (-2850 750);
FORCEPROP 1 LAST BODY_TYPE PLUMBING
J 2
(-2850 700);
DISPLAY 1.595745 (-2850 700);
PAINT GREEN (-2850 700);
DISPLAY INVISIBLE (-2850 700);
FORCEPROP 1 LAST HDL_TAP TRUE
J 2
(-3175 625);
DISPLAY 1.595745 (-3175 625);
PAINT GREEN (-3175 625);
DISPLAY INVISIBLE (-3175 625);
FORCEPROP 1 LAST PATH I87
J 2
(-2848 750);
DISPLAY 0.872340 (-2848 750);
PAINT GREEN (-2848 750);
DISPLAY INVISIBLE (-2848 750);
FORCEADD TAP..6
R 2
(-2850 700);
FORCEPROP 3 LASTPIN (-2900 700) SIG_NAME M_J_BA<0>
J 0
(-2890 710);
DISPLAY 0.659574 (-2890 710);
PAINT MONO (-2890 710);
DISPLAY INVISIBLE (-2890 710);
FORCEPROP 1 LASTPIN (-2900 700) BN 0
J 2
(-2848 708);
DISPLAY 0.617021 (-2848 708);
PAINT GREEN (-2848 708);
FORCEPROP 2 LAST CDS_LIB mstr_standard
J 0
(-2850 700);
PAINT MONO (-2850 700);
DISPLAY INVISIBLE (-2850 700);
FORCEPROP 1 LAST BODY_TYPE PLUMBING
J 2
(-2850 650);
DISPLAY 1.595745 (-2850 650);
PAINT GREEN (-2850 650);
DISPLAY INVISIBLE (-2850 650);
FORCEPROP 1 LAST HDL_TAP TRUE
J 2
(-3175 575);
DISPLAY 1.595745 (-3175 575);
PAINT GREEN (-3175 575);
DISPLAY INVISIBLE (-3175 575);
FORCEPROP 1 LAST PATH I88
J 2
(-2848 700);
DISPLAY 0.872340 (-2848 700);
PAINT GREEN (-2848 700);
DISPLAY INVISIBLE (-2848 700);
FORCEADD TAP..6
R 2
(-2850 800);
FORCEPROP 3 LASTPIN (-2900 800) SIG_NAME M_J_BG<0>
J 0
(-2890 810);
DISPLAY 0.659574 (-2890 810);
PAINT MONO (-2890 810);
DISPLAY INVISIBLE (-2890 810);
FORCEPROP 1 LASTPIN (-2900 800) BN 0
J 2
(-2848 808);
DISPLAY 0.617021 (-2848 808);
PAINT GREEN (-2848 808);
FORCEPROP 2 LAST CDS_LIB mstr_standard
J 0
(-2850 800);
PAINT MONO (-2850 800);
DISPLAY INVISIBLE (-2850 800);
FORCEPROP 1 LAST BODY_TYPE PLUMBING
J 2
(-2850 750);
DISPLAY 1.595745 (-2850 750);
PAINT GREEN (-2850 750);
DISPLAY INVISIBLE (-2850 750);
FORCEPROP 1 LAST HDL_TAP TRUE
J 2
(-3175 675);
DISPLAY 1.595745 (-3175 675);
PAINT GREEN (-3175 675);
DISPLAY INVISIBLE (-3175 675);
FORCEPROP 1 LAST PATH I89
J 2
(-2848 800);
DISPLAY 0.872340 (-2848 800);
PAINT GREEN (-2848 800);
DISPLAY INVISIBLE (-2848 800);
FORCEADD TAP..6
(-5575 850);
FORCEPROP 3 LASTPIN (-5525 850) SIG_NAME M_J_CLK_DP<1>
J 0
(-5515 860);
DISPLAY 0.659574 (-5515 860);
PAINT MONO (-5515 860);
DISPLAY INVISIBLE (-5515 860);
FORCEPROP 1 LASTPIN (-5525 850) BN 1
J 0
(-5577 858);
DISPLAY 0.617021 (-5577 858);
PAINT GREEN (-5577 858);
FORCEPROP 2 LAST CDS_LIB mstr_standard
J 0
(-5575 850);
PAINT MONO (-5575 850);
DISPLAY INVISIBLE (-5575 850);
FORCEPROP 1 LAST BODY_TYPE PLUMBING
J 0
(-5575 800);
DISPLAY 1.595745 (-5575 800);
PAINT GREEN (-5575 800);
DISPLAY INVISIBLE (-5575 800);
FORCEPROP 1 LAST HDL_TAP TRUE
J 0
(-5250 725);
DISPLAY 1.595745 (-5250 725);
PAINT GREEN (-5250 725);
DISPLAY INVISIBLE (-5250 725);
FORCEPROP 1 LAST PATH I9
J 0
(-5577 850);
DISPLAY 0.872340 (-5577 850);
PAINT GREEN (-5577 850);
DISPLAY INVISIBLE (-5577 850);
FORCEADD TAP..6
R 2
(-2850 850);
FORCEPROP 3 LASTPIN (-2900 850) SIG_NAME M_J_BG<1>
J 0
(-2890 860);
DISPLAY 0.659574 (-2890 860);
PAINT MONO (-2890 860);
DISPLAY INVISIBLE (-2890 860);
FORCEPROP 1 LASTPIN (-2900 850) BN 1
J 2
(-2848 858);
DISPLAY 0.617021 (-2848 858);
PAINT GREEN (-2848 858);
FORCEPROP 2 LAST CDS_LIB mstr_standard
J 0
(-2850 850);
PAINT MONO (-2850 850);
DISPLAY INVISIBLE (-2850 850);
FORCEPROP 1 LAST BODY_TYPE PLUMBING
J 2
(-2850 800);
DISPLAY 1.595745 (-2850 800);
PAINT GREEN (-2850 800);
DISPLAY INVISIBLE (-2850 800);
FORCEPROP 1 LAST HDL_TAP TRUE
J 2
(-3175 725);
DISPLAY 1.595745 (-3175 725);
PAINT GREEN (-3175 725);
DISPLAY INVISIBLE (-3175 725);
FORCEPROP 1 LAST PATH I90
J 2
(-2848 850);
DISPLAY 0.872340 (-2848 850);
PAINT GREEN (-2848 850);
DISPLAY INVISIBLE (-2848 850);
FORCEADD TAP..6
R 2
(-2850 1050);
FORCEPROP 3 LASTPIN (-2900 1050) SIG_NAME M_J_CS_N<2>
J 0
(-2890 1060);
DISPLAY 0.659574 (-2890 1060);
PAINT MONO (-2890 1060);
DISPLAY INVISIBLE (-2890 1060);
FORCEPROP 1 LASTPIN (-2900 1050) BN 2
J 2
(-2848 1058);
DISPLAY 0.617021 (-2848 1058);
PAINT GREEN (-2848 1058);
FORCEPROP 2 LAST CDS_LIB mstr_standard
J 0
(-2850 1050);
PAINT MONO (-2850 1050);
DISPLAY INVISIBLE (-2850 1050);
FORCEPROP 1 LAST BODY_TYPE PLUMBING
J 2
(-2850 1000);
DISPLAY 1.595745 (-2850 1000);
PAINT GREEN (-2850 1000);
DISPLAY INVISIBLE (-2850 1000);
FORCEPROP 1 LAST HDL_TAP TRUE
J 2
(-3175 925);
DISPLAY 1.595745 (-3175 925);
PAINT GREEN (-3175 925);
DISPLAY INVISIBLE (-3175 925);
FORCEPROP 1 LAST PATH I91
J 2
(-2848 1050);
DISPLAY 0.872340 (-2848 1050);
PAINT GREEN (-2848 1050);
DISPLAY INVISIBLE (-2848 1050);
FORCEADD TAP..6
R 2
(-2850 1000);
FORCEPROP 3 LASTPIN (-2900 1000) SIG_NAME M_J_CS_N<1>
J 0
(-2890 1010);
DISPLAY 0.659574 (-2890 1010);
PAINT MONO (-2890 1010);
DISPLAY INVISIBLE (-2890 1010);
FORCEPROP 1 LASTPIN (-2900 1000) BN 1
J 2
(-2848 1008);
DISPLAY 0.617021 (-2848 1008);
PAINT GREEN (-2848 1008);
FORCEPROP 2 LAST CDS_LIB mstr_standard
J 0
(-2850 1000);
PAINT MONO (-2850 1000);
DISPLAY INVISIBLE (-2850 1000);
FORCEPROP 1 LAST BODY_TYPE PLUMBING
J 2
(-2850 950);
DISPLAY 1.595745 (-2850 950);
PAINT GREEN (-2850 950);
DISPLAY INVISIBLE (-2850 950);
FORCEPROP 1 LAST HDL_TAP TRUE
J 2
(-3175 875);
DISPLAY 1.595745 (-3175 875);
PAINT GREEN (-3175 875);
DISPLAY INVISIBLE (-3175 875);
FORCEPROP 1 LAST PATH I92
J 2
(-2848 1000);
DISPLAY 0.872340 (-2848 1000);
PAINT GREEN (-2848 1000);
DISPLAY INVISIBLE (-2848 1000);
FORCEADD TAP..6
R 2
(-2850 950);
FORCEPROP 3 LASTPIN (-2900 950) SIG_NAME M_J_CS_N<0>
J 0
(-2890 960);
DISPLAY 0.659574 (-2890 960);
PAINT MONO (-2890 960);
DISPLAY INVISIBLE (-2890 960);
FORCEPROP 1 LASTPIN (-2900 950) BN 0
J 2
(-2848 958);
DISPLAY 0.617021 (-2848 958);
PAINT GREEN (-2848 958);
FORCEPROP 2 LAST CDS_LIB mstr_standard
J 0
(-2850 950);
PAINT MONO (-2850 950);
DISPLAY INVISIBLE (-2850 950);
FORCEPROP 1 LAST BODY_TYPE PLUMBING
J 2
(-2850 900);
DISPLAY 1.595745 (-2850 900);
PAINT GREEN (-2850 900);
DISPLAY INVISIBLE (-2850 900);
FORCEPROP 1 LAST HDL_TAP TRUE
J 2
(-3175 825);
DISPLAY 1.595745 (-3175 825);
PAINT GREEN (-3175 825);
DISPLAY INVISIBLE (-3175 825);
FORCEPROP 1 LAST PATH I93
J 2
(-2848 950);
DISPLAY 0.872340 (-2848 950);
PAINT GREEN (-2848 950);
DISPLAY INVISIBLE (-2848 950);
FORCEADD TAP..6
R 2
(-2850 1150);
FORCEPROP 3 LASTPIN (-2900 1150) SIG_NAME M_J_CS_N<4>
J 0
(-2890 1160);
DISPLAY 0.659574 (-2890 1160);
PAINT MONO (-2890 1160);
DISPLAY INVISIBLE (-2890 1160);
FORCEPROP 1 LASTPIN (-2900 1150) BN 4
J 2
(-2848 1158);
DISPLAY 0.617021 (-2848 1158);
PAINT GREEN (-2848 1158);
FORCEPROP 2 LAST CDS_LIB mstr_standard
J 0
(-2850 1150);
PAINT MONO (-2850 1150);
DISPLAY INVISIBLE (-2850 1150);
FORCEPROP 1 LAST BODY_TYPE PLUMBING
J 2
(-2850 1100);
DISPLAY 1.595745 (-2850 1100);
PAINT GREEN (-2850 1100);
DISPLAY INVISIBLE (-2850 1100);
FORCEPROP 1 LAST HDL_TAP TRUE
J 2
(-3175 1025);
DISPLAY 1.595745 (-3175 1025);
PAINT GREEN (-3175 1025);
DISPLAY INVISIBLE (-3175 1025);
FORCEPROP 1 LAST PATH I94
J 2
(-2848 1150);
DISPLAY 0.872340 (-2848 1150);
PAINT GREEN (-2848 1150);
DISPLAY INVISIBLE (-2848 1150);
FORCEADD TAP..6
R 2
(-2850 1100);
FORCEPROP 3 LASTPIN (-2900 1100) SIG_NAME M_J_CS_N<3>
J 0
(-2890 1110);
DISPLAY 0.659574 (-2890 1110);
PAINT MONO (-2890 1110);
DISPLAY INVISIBLE (-2890 1110);
FORCEPROP 1 LASTPIN (-2900 1100) BN 3
J 2
(-2848 1108);
DISPLAY 0.617021 (-2848 1108);
PAINT GREEN (-2848 1108);
FORCEPROP 2 LAST CDS_LIB mstr_standard
J 0
(-2850 1100);
PAINT MONO (-2850 1100);
DISPLAY INVISIBLE (-2850 1100);
FORCEPROP 1 LAST BODY_TYPE PLUMBING
J 2
(-2850 1050);
DISPLAY 1.595745 (-2850 1050);
PAINT GREEN (-2850 1050);
DISPLAY INVISIBLE (-2850 1050);
FORCEPROP 1 LAST HDL_TAP TRUE
J 2
(-3175 975);
DISPLAY 1.595745 (-3175 975);
PAINT GREEN (-3175 975);
DISPLAY INVISIBLE (-3175 975);
FORCEPROP 1 LAST PATH I95
J 2
(-2848 1100);
DISPLAY 0.872340 (-2848 1100);
PAINT GREEN (-2848 1100);
DISPLAY INVISIBLE (-2848 1100);
FORCEADD TAP..6
R 2
(-2850 1200);
FORCEPROP 3 LASTPIN (-2900 1200) SIG_NAME M_J_CS_N<5>
J 0
(-2890 1210);
DISPLAY 0.659574 (-2890 1210);
PAINT MONO (-2890 1210);
DISPLAY INVISIBLE (-2890 1210);
FORCEPROP 1 LASTPIN (-2900 1200) BN 5
J 2
(-2848 1208);
DISPLAY 0.617021 (-2848 1208);
PAINT GREEN (-2848 1208);
FORCEPROP 2 LAST CDS_LIB mstr_standard
J 0
(-2850 1200);
PAINT MONO (-2850 1200);
DISPLAY INVISIBLE (-2850 1200);
FORCEPROP 1 LAST BODY_TYPE PLUMBING
J 2
(-2850 1150);
DISPLAY 1.595745 (-2850 1150);
PAINT GREEN (-2850 1150);
DISPLAY INVISIBLE (-2850 1150);
FORCEPROP 1 LAST HDL_TAP TRUE
J 2
(-3175 1075);
DISPLAY 1.595745 (-3175 1075);
PAINT GREEN (-3175 1075);
DISPLAY INVISIBLE (-3175 1075);
FORCEPROP 1 LAST PATH I96
J 2
(-2848 1200);
DISPLAY 0.872340 (-2848 1200);
PAINT GREEN (-2848 1200);
DISPLAY INVISIBLE (-2848 1200);
FORCEADD TAP..6
R 2
(-2850 1250);
FORCEPROP 3 LASTPIN (-2900 1250) SIG_NAME M_J_CS_N<6>
J 0
(-2890 1260);
DISPLAY 0.659574 (-2890 1260);
PAINT MONO (-2890 1260);
DISPLAY INVISIBLE (-2890 1260);
FORCEPROP 1 LASTPIN (-2900 1250) BN 6
J 2
(-2848 1258);
DISPLAY 0.617021 (-2848 1258);
PAINT GREEN (-2848 1258);
FORCEPROP 2 LAST CDS_LIB mstr_standard
J 0
(-2850 1250);
PAINT MONO (-2850 1250);
DISPLAY INVISIBLE (-2850 1250);
FORCEPROP 1 LAST BODY_TYPE PLUMBING
J 2
(-2850 1200);
DISPLAY 1.595745 (-2850 1200);
PAINT GREEN (-2850 1200);
DISPLAY INVISIBLE (-2850 1200);
FORCEPROP 1 LAST HDL_TAP TRUE
J 2
(-3175 1125);
DISPLAY 1.595745 (-3175 1125);
PAINT GREEN (-3175 1125);
DISPLAY INVISIBLE (-3175 1125);
FORCEPROP 1 LAST PATH I97
J 2
(-2848 1250);
DISPLAY 0.872340 (-2848 1250);
PAINT GREEN (-2848 1250);
DISPLAY INVISIBLE (-2848 1250);
FORCEADD TAP..6
R 2
(-2850 1300);
FORCEPROP 3 LASTPIN (-2900 1300) SIG_NAME M_J_CS_N<7>
J 0
(-2890 1310);
DISPLAY 0.659574 (-2890 1310);
PAINT MONO (-2890 1310);
DISPLAY INVISIBLE (-2890 1310);
FORCEPROP 1 LASTPIN (-2900 1300) BN 7
J 2
(-2848 1308);
DISPLAY 0.617021 (-2848 1308);
PAINT GREEN (-2848 1308);
FORCEPROP 2 LAST CDS_LIB mstr_standard
J 0
(-2850 1300);
PAINT MONO (-2850 1300);
DISPLAY INVISIBLE (-2850 1300);
FORCEPROP 1 LAST BODY_TYPE PLUMBING
J 2
(-2850 1250);
DISPLAY 1.595745 (-2850 1250);
PAINT GREEN (-2850 1250);
DISPLAY INVISIBLE (-2850 1250);
FORCEPROP 1 LAST HDL_TAP TRUE
J 2
(-3175 1175);
DISPLAY 1.595745 (-3175 1175);
PAINT GREEN (-3175 1175);
DISPLAY INVISIBLE (-3175 1175);
FORCEPROP 1 LAST PATH I98
J 2
(-2848 1300);
DISPLAY 0.872340 (-2848 1300);
PAINT GREEN (-2848 1300);
DISPLAY INVISIBLE (-2848 1300);
FORCEADD TAP..6
R 2
(-2850 1400);
FORCEPROP 3 LASTPIN (-2900 1400) SIG_NAME M_J_ODT<0>
J 0
(-2890 1410);
DISPLAY 0.659574 (-2890 1410);
PAINT MONO (-2890 1410);
DISPLAY INVISIBLE (-2890 1410);
FORCEPROP 1 LASTPIN (-2900 1400) BN 0
J 2
(-2848 1408);
DISPLAY 0.617021 (-2848 1408);
PAINT GREEN (-2848 1408);
FORCEPROP 2 LAST CDS_LIB mstr_standard
J 0
(-2850 1400);
PAINT MONO (-2850 1400);
DISPLAY INVISIBLE (-2850 1400);
FORCEPROP 1 LAST BODY_TYPE PLUMBING
J 2
(-2850 1350);
DISPLAY 1.595745 (-2850 1350);
PAINT GREEN (-2850 1350);
DISPLAY INVISIBLE (-2850 1350);
FORCEPROP 1 LAST HDL_TAP TRUE
J 2
(-3175 1275);
DISPLAY 1.595745 (-3175 1275);
PAINT GREEN (-3175 1275);
DISPLAY INVISIBLE (-3175 1275);
FORCEPROP 1 LAST PATH I99
J 2
(-2848 1400);
DISPLAY 0.872340 (-2848 1400);
PAINT GREEN (-2848 1400);
DISPLAY INVISIBLE (-2848 1400);
FORCEADD DESIGN_NOTE..1
(-6325 375);
FORCEPROP 0 LAST L1 CPU SYMBOLS 1-30 ARE PRELIMINARY AND SUBJECT TO CHANGE
J 0
(-6525 250);
DISPLAY 1.021277 (-6525 250);
PAINT ORANGE (-6525 250);
FORCEPROP 2 LAST CDS_LIB mstr_symbols
J 0
(-6325 375);
PAINT ORANGE (-6325 375);
DISPLAY INVISIBLE (-6325 375);
FORCEPROP 1 LAST COMMENT_BODY TRUE
J 0
(-6300 475);
DISPLAY 0.978723 (-6300 475);
PAINT ORANGE (-6300 475);
DISPLAY INVISIBLE (-6300 475);
FORCEADD INTEL_CORP_BPAGE..1
(0 0);
FORCEPROP 1 LAST CDS_CON_LAST_MODIFIED Fri Jun 16 17:48:23 2017
J 0
(-1425 325);
DISPLAY 1.340426 (-1425 325);
PAINT GREEN (-1425 325);
DISPLAY INVISIBLE (-1425 325);
FORCEPROP 1 LAST CUSTOM_TXT_CDS <CURRENT_DESIGN_SHEET> OF <TOTAL_DESIGN_SHEETS>
J 0
(-500 25);
PAINT ORANGE (-500 25);
FORCEPROP 1 LAST CUSTOM_TXT_CDS <CON_LAST_MODIFIED>
J 0
(-4000 100);
PAINT ORANGE (-4000 100);
FORCEPROP 2 LAST CUSTOM_TXT_CDS <XR_PAGE_TITLE>
J 0
(-7890 5250);
DISPLAY 0.638298 (-7890 5250);
PAINT PINK (-7890 5250);
DISPLAY INVISIBLE (-7890 5250);
FORCEPROP 1 LAST SCH_TITLE SKYLAKE - SKT1 - 5 OF 21
J 0
(-7950 50);
DISPLAY 1.212766 (-7950 50);
PAINT GREEN (-7950 50);
FORCEPROP 2 LAST CDS_LIB mstr_symbols
J 0
(0 0);
PAINT ORANGE (0 0);
DISPLAY INVISIBLE (0 0);
FORCEPROP 2 LAST PAGE_BORDER TRUE
J 0
(-7890 5250);
DISPLAY 0.851064 (-7890 5250);
PAINT PINK (-7890 5250);
DISPLAY INVISIBLE (-7890 5250);
FORCEPROP 1 LAST COMMENT_BODY TRUE
J 0
(12 12);
DISPLAY 0.638298 (12 12);
PAINT GREEN (12 12);
DISPLAY INVISIBLE (12 12);
FORCEPROP 2 LAST CDS_XR_PAGE_TITLE CR-59 : @BASEBOARD_FAB2_LIB.BASEBOARD_FAB2(SCH_1):PAGE59
J 0
(-7890 5250);
DISPLAY 0.638298 (-7890 5250);
PAINT PINK (-7890 5250);
DISPLAY INVISIBLE (-7890 5250);
FORCEADD PRELIM..10
(-4215 2540);
PAINT GRAY (-4215 2540);
FORCEPROP 2 LAST CDS_LIB mstr_misc
J 0
(-4215 2540);
PAINT ORANGE (-4215 2540);
DISPLAY INVISIBLE (-4215 2540);
FORCEPROP 1 LAST COMMENT_BODY TRUE
J 0
(-4215 2540);
PAINT ORANGE (-4215 2540);
DISPLAY INVISIBLE (-4215 2540);
WIRE 17 -1 (-2800 3825)(-2800 3875);
WIRE 17 -1 (-2800 3875)(-2800 3925);
WIRE 17 -1 (-2800 3925)(-2800 3975);
WIRE 17 -1 (-2800 3975)(-2800 4025);
WIRE 17 -1 (-2800 4025)(-2800 4075);
WIRE 17 -1 (-2800 4075)(-2800 4125);
WIRE 17 -1 (-2800 4125)(-2800 4175);
WIRE 17 -1 (-2800 4175)(-2800 4225);
WIRE 17 -1 (-2800 4225)(-2800 4275);
WIRE 17 -1 (-2800 4275)(-2800 4325);
WIRE 17 -1 (-2800 4325)(-2800 4375);
WIRE 17 -1 (-2800 4375)(-2800 4425);
WIRE 17 -1 (-2800 4425)(-2800 4475);
WIRE 17 -1 (-2800 4475)(-2800 4525);
WIRE 17 -1 (-2800 4525)(-2800 4575);
WIRE 17 -1 (-2800 4575)(-2800 4625);
WIRE 17 -1 (-2050 4725)(-2800 4725);
FORCEPROP 2 LAST SIG_NAME M_J_DQS_DP<17:0>
J 0
(-2700 4735);
DISPLAY 0.617021 (-2700 4735);
PAINT ORANGE (-2700 4735);
WIRE 17 -1 (-2800 4625)(-2800 4675);
WIRE 17 -1 (-2800 4675)(-2800 4725);
WIRE 17 -1 (-2800 2875)(-2800 2925);
WIRE 17 -1 (-2800 2925)(-2800 2975);
WIRE 17 -1 (-2800 2975)(-2800 3025);
WIRE 17 -1 (-2800 3025)(-2800 3075);
WIRE 17 -1 (-2800 3075)(-2800 3125);
WIRE 17 -1 (-2800 3125)(-2800 3175);
WIRE 17 -1 (-2800 3175)(-2800 3225);
WIRE 17 -1 (-2800 3225)(-2800 3275);
WIRE 17 -1 (-2800 3275)(-2800 3325);
WIRE 17 -1 (-2800 3325)(-2800 3375);
WIRE 17 -1 (-2800 3375)(-2800 3425);
WIRE 17 -1 (-2800 3425)(-2800 3475);
WIRE 17 -1 (-2800 3475)(-2800 3525);
WIRE 17 -1 (-2800 3525)(-2800 3575);
WIRE 17 -1 (-2800 3575)(-2800 3625);
WIRE 17 -1 (-2800 3625)(-2800 3675);
WIRE 17 -1 (-2050 3750)(-2800 3750);
FORCEPROP 2 LAST SIG_NAME M_J_DQS_DN<17:0>
J 0
(-2700 3760);
DISPLAY 0.617021 (-2700 3760);
PAINT ORANGE (-2700 3760);
WIRE 17 -1 (-2800 3675)(-2800 3725);
WIRE 17 -1 (-2800 3725)(-2800 3750);
WIRE 17 -1 (-2800 1925)(-2800 1975);
WIRE 17 -1 (-2800 1975)(-2800 2025);
WIRE 17 -1 (-2800 2025)(-2800 2075);
WIRE 17 -1 (-2800 2075)(-2800 2125);
WIRE 17 -1 (-2800 2125)(-2800 2175);
WIRE 17 -1 (-2800 2175)(-2800 2225);
WIRE 17 -1 (-2800 2225)(-2800 2275);
WIRE 17 -1 (-2800 2275)(-2800 2325);
WIRE 17 -1 (-2800 2325)(-2800 2375);
WIRE 17 -1 (-2800 2375)(-2800 2425);
WIRE 17 -1 (-2800 2425)(-2800 2475);
WIRE 17 -1 (-2800 2475)(-2800 2525);
WIRE 17 -1 (-2800 2525)(-2800 2575);
WIRE 17 -1 (-2800 2575)(-2800 2625);
WIRE 17 -1 (-2800 2625)(-2800 2675);
WIRE 17 -1 (-2800 2675)(-2800 2725);
WIRE 17 -1 (-2050 2800)(-2800 2800);
FORCEPROP 2 LAST SIG_NAME M_J_MA<17:0>
J 0
(-2700 2810);
DISPLAY 0.617021 (-2700 2810);
PAINT ORANGE (-2700 2810);
WIRE 17 -1 (-2800 2725)(-2800 2775);
WIRE 17 -1 (-2800 2775)(-2800 2800);
WIRE 17 -1 (-2050 800)(-2800 800);
FORCEPROP 2 LAST SIG_NAME M_J_BA<1:0>
J 0
(-2700 810);
DISPLAY 0.617021 (-2700 810);
PAINT ORANGE (-2700 810);
WIRE 17 -1 (-2800 725)(-2800 775);
WIRE 17 -1 (-2800 775)(-2800 800);
WIRE 17 -1 (-2050 900)(-2800 900);
FORCEPROP 2 LAST SIG_NAME M_J_BG<1:0>
J 0
(-2700 910);
DISPLAY 0.617021 (-2700 910);
PAINT ORANGE (-2700 910);
WIRE 17 -1 (-2800 875)(-2800 900);
WIRE 17 -1 (-2800 825)(-2800 875);
WIRE 17 -1 (-2800 1675)(-2800 1725);
WIRE 17 -1 (-2800 1725)(-2800 1775);
WIRE 17 -1 (-2050 1850)(-2800 1850);
FORCEPROP 2 LAST SIG_NAME M_J_CKE <3:0>
J 0
(-2700 1860);
DISPLAY 0.617021 (-2700 1860);
PAINT ORANGE (-2700 1860);
WIRE 17 -1 (-2800 1775)(-2800 1825);
WIRE 17 -1 (-2800 1825)(-2800 1850);
WIRE 17 -1 (-2800 975)(-2800 1025);
WIRE 17 -1 (-2800 1025)(-2800 1075);
WIRE 17 -1 (-2800 1075)(-2800 1125);
WIRE 17 -1 (-2800 1125)(-2800 1175);
WIRE 17 -1 (-2800 1175)(-2800 1225);
WIRE 17 -1 (-2800 1225)(-2800 1275);
WIRE 17 -1 (-2050 1350)(-2800 1350);
FORCEPROP 2 LAST SIG_NAME M_J_CS_N<7:0>
J 0
(-2700 1360);
DISPLAY 0.617021 (-2700 1360);
PAINT ORANGE (-2700 1360);
WIRE 17 -1 (-2800 1275)(-2800 1325);
WIRE 17 -1 (-2800 1325)(-2800 1350);
WIRE 17 -1 (-2800 1425)(-2800 1475);
WIRE 17 -1 (-2050 1600)(-2800 1600);
FORCEPROP 2 LAST SIG_NAME M_J_ODT<3:0>
J 0
(-2700 1610);
DISPLAY 0.617021 (-2700 1610);
PAINT ORANGE (-2700 1610);
WIRE 17 -1 (-2800 1575)(-2800 1600);
WIRE 17 -1 (-2800 1475)(-2800 1525);
WIRE 17 -1 (-2800 1525)(-2800 1575);
WIRE 17 -1 (-5625 1525)(-5625 1575);
WIRE 17 -1 (-5625 1575)(-5625 1625);
WIRE 17 -1 (-5625 1625)(-5625 1675);
WIRE 17 -1 (-5625 1675)(-5625 1725);
WIRE 17 -1 (-5625 1725)(-5625 1775);
WIRE 17 -1 (-5625 1775)(-5625 1825);
WIRE 17 -1 (-5625 1825)(-5625 1875);
WIRE 17 -1 (-5625 1875)(-5625 1925);
WIRE 17 -1 (-5625 1925)(-5625 1975);
WIRE 17 -1 (-5625 1975)(-5625 2025);
WIRE 17 -1 (-5625 2025)(-5625 2075);
WIRE 17 -1 (-5625 2075)(-5625 2125);
WIRE 17 -1 (-5625 2125)(-5625 2175);
WIRE 17 -1 (-5625 2175)(-5625 2225);
WIRE 17 -1 (-5625 2225)(-5625 2275);
WIRE 17 -1 (-5625 2275)(-5625 2325);
WIRE 17 -1 (-5625 2325)(-5625 2375);
WIRE 17 -1 (-5625 2375)(-5625 2425);
WIRE 17 -1 (-5625 2425)(-5625 2475);
WIRE 17 -1 (-5625 2475)(-5625 2525);
WIRE 17 -1 (-5625 2525)(-5625 2575);
WIRE 17 -1 (-5625 2575)(-5625 2625);
WIRE 17 -1 (-5625 2625)(-5625 2675);
WIRE 17 -1 (-5625 2675)(-5625 2725);
WIRE 17 -1 (-5625 2725)(-5625 2775);
WIRE 17 -1 (-5625 2775)(-5625 2825);
WIRE 17 -1 (-5625 2825)(-5625 2875);
WIRE 17 -1 (-5625 2875)(-5625 2925);
WIRE 17 -1 (-5625 2925)(-5625 2975);
WIRE 17 -1 (-5625 2975)(-5625 3025);
WIRE 17 -1 (-5625 3025)(-5625 3075);
WIRE 17 -1 (-5625 3075)(-5625 3125);
WIRE 17 -1 (-5625 3125)(-5625 3175);
WIRE 17 -1 (-5625 3175)(-5625 3225);
WIRE 17 -1 (-5625 3225)(-5625 3275);
WIRE 17 -1 (-5625 3275)(-5625 3325);
WIRE 17 -1 (-5625 3325)(-5625 3375);
WIRE 17 -1 (-5625 3375)(-5625 3425);
WIRE 17 -1 (-5625 3425)(-5625 3475);
WIRE 17 -1 (-5625 3475)(-5625 3525);
WIRE 17 -1 (-5625 3525)(-5625 3575);
WIRE 17 -1 (-5625 3575)(-5625 3625);
WIRE 17 -1 (-5625 3625)(-5625 3675);
WIRE 17 -1 (-5625 3675)(-5625 3725);
WIRE 17 -1 (-5625 3725)(-5625 3775);
WIRE 17 -1 (-5625 3775)(-5625 3825);
WIRE 17 -1 (-5625 3825)(-5625 3875);
WIRE 17 -1 (-5625 3875)(-5625 3925);
WIRE 17 -1 (-5625 3925)(-5625 3975);
WIRE 17 -1 (-5625 3975)(-5625 4025);
WIRE 17 -1 (-5625 4025)(-5625 4075);
WIRE 17 -1 (-5625 4075)(-5625 4125);
WIRE 17 -1 (-5625 4125)(-5625 4175);
WIRE 17 -1 (-5625 4175)(-5625 4225);
WIRE 17 -1 (-5625 4225)(-5625 4275);
WIRE 17 -1 (-5625 4275)(-5625 4325);
WIRE 17 -1 (-5625 4325)(-5625 4375);
WIRE 17 -1 (-5625 4375)(-5625 4425);
WIRE 17 -1 (-5625 4425)(-5625 4475);
WIRE 17 -1 (-5625 4475)(-5625 4525);
WIRE 17 -1 (-5625 4525)(-5625 4575);
WIRE 17 -1 (-5625 4575)(-5625 4625);
WIRE 17 -1 (-5625 4775)(-6375 4775);
FORCEPROP 2 LAST SIG_NAME M_J_DQ<63:0>
J 0
(-6325 4785);
DISPLAY 0.617021 (-6325 4785);
PAINT ORANGE (-6325 4785);
WIRE 17 -1 (-5625 4625)(-5625 4675);
WIRE 17 -1 (-5625 4675)(-5625 4775);
WIRE 17 -1 (-5625 625)(-5625 675);
WIRE 17 -1 (-5625 675)(-5625 725);
WIRE 17 -1 (-5625 800)(-6375 800);
FORCEPROP 2 LAST SIG_NAME M_J_CLK_DN<3:0>
J 0
(-6325 810);
DISPLAY 0.617021 (-6325 810);
PAINT ORANGE (-6325 810);
WIRE 17 -1 (-5625 725)(-5625 775);
WIRE 17 -1 (-5625 775)(-5625 800);
WIRE 17 -1 (-5625 825)(-5625 875);
WIRE 17 -1 (-5625 875)(-5625 925);
WIRE 17 -1 (-5625 1000)(-6375 1000);
FORCEPROP 2 LAST SIG_NAME M_J_CLK_DP<3:0>
J 0
(-6325 1010);
DISPLAY 0.617021 (-6325 1010);
PAINT ORANGE (-6325 1010);
WIRE 17 -1 (-5625 925)(-5625 975);
WIRE 17 -1 (-5625 975)(-5625 1000);
WIRE 17 -1 (-5625 1075)(-5625 1125);
WIRE 17 -1 (-5625 1125)(-5625 1175);
WIRE 17 -1 (-5625 1175)(-5625 1225);
WIRE 17 -1 (-5625 1225)(-5625 1275);
WIRE 17 -1 (-5625 1275)(-5625 1325);
WIRE 17 -1 (-5625 1325)(-5625 1375);
WIRE 17 -1 (-5625 1450)(-6375 1450);
FORCEPROP 2 LAST SIG_NAME M_J_ECC<7:0>
J 0
(-6325 1460);
DISPLAY 0.617021 (-6325 1460);
PAINT ORANGE (-6325 1460);
WIRE 17 -1 (-5625 1375)(-5625 1425);
WIRE 17 -1 (-5625 1425)(-5625 1450);
WIRE 16 -1 (-3325 3250)(-2900 3250);
WIRE 16 -1 (-5025 4250)(-5525 4250);
WIRE 16 -1 (-5525 3550)(-5025 3550);
WIRE 16 -1 (-5025 4150)(-5525 4150);
WIRE 16 -1 (-3325 1550)(-2900 1550);
WIRE 16 -1 (-5525 3250)(-5025 3250);
WIRE 16 -1 (-5525 3150)(-5025 3150);
WIRE 16 -1 (-5025 500)(-6375 500);
FORCEPROP 2 LAST SIG_NAME M_J_C<2>
J 0
(-6325 510);
DISPLAY 0.617021 (-6325 510);
PAINT ORANGE (-6325 510);
WIRE 16 -1 (-5025 1050)(-5525 1050);
WIRE 16 -1 (-5025 1100)(-5525 1100);
WIRE 16 -1 (-5025 1150)(-5525 1150);
WIRE 16 -1 (-5025 1200)(-5525 1200);
WIRE 16 -1 (-5025 1250)(-5525 1250);
WIRE 16 -1 (-5025 1300)(-5525 1300);
WIRE 16 -1 (-5025 1350)(-5525 1350);
WIRE 16 -1 (-5025 1400)(-5525 1400);
WIRE 16 -1 (-5525 1500)(-5025 1500);
WIRE 16 -1 (-5525 1550)(-5025 1550);
WIRE 16 -1 (-5525 1600)(-5025 1600);
WIRE 16 -1 (-5025 1650)(-5525 1650);
WIRE 16 -1 (-5525 1700)(-5025 1700);
WIRE 16 -1 (-5525 1750)(-5025 1750);
WIRE 16 -1 (-5025 1800)(-5525 1800);
WIRE 16 -1 (-5525 1850)(-5025 1850);
WIRE 16 -1 (-5525 1900)(-5025 1900);
WIRE 16 -1 (-5525 1950)(-5025 1950);
WIRE 16 -1 (-5525 2000)(-5025 2000);
WIRE 16 -1 (-5025 800)(-5525 800);
WIRE 16 -1 (-5025 850)(-5525 850);
WIRE 16 -1 (-5025 900)(-5525 900);
WIRE 16 -1 (-5025 950)(-5525 950);
WIRE 16 -1 (-5025 600)(-5525 600);
WIRE 16 -1 (-5025 650)(-5525 650);
WIRE 16 -1 (-5025 700)(-5525 700);
WIRE 16 -1 (-5025 750)(-5525 750);
WIRE 16 -1 (-5525 2050)(-5025 2050);
WIRE 16 -1 (-5525 2100)(-5025 2100);
WIRE 16 -1 (-5525 2150)(-5025 2150);
WIRE 16 -1 (-5525 2200)(-5025 2200);
WIRE 16 -1 (-5025 2250)(-5525 2250);
WIRE 16 -1 (-5525 2300)(-5025 2300);
WIRE 16 -1 (-5525 2350)(-5025 2350);
WIRE 16 -1 (-5025 2400)(-5525 2400);
WIRE 16 -1 (-5525 2450)(-5025 2450);
WIRE 16 -1 (-5525 2500)(-5025 2500);
WIRE 16 -1 (-5525 2550)(-5025 2550);
WIRE 16 -1 (-5525 2600)(-5025 2600);
WIRE 16 -1 (-5025 2650)(-5525 2650);
WIRE 16 -1 (-5525 2700)(-5025 2700);
WIRE 16 -1 (-5525 2750)(-5025 2750);
WIRE 16 -1 (-5525 2800)(-5025 2800);
WIRE 16 -1 (-5525 2850)(-5025 2850);
WIRE 16 -1 (-5525 2900)(-5025 2900);
WIRE 16 -1 (-5525 2950)(-5025 2950);
WIRE 16 -1 (-5025 3000)(-5525 3000);
WIRE 16 -1 (-5525 3050)(-5025 3050);
WIRE 16 -1 (-5525 3100)(-5025 3100);
WIRE 16 -1 (-5525 3200)(-5025 3200);
WIRE 16 -1 (-5525 3300)(-5025 3300);
WIRE 16 -1 (-5025 3350)(-5525 3350);
WIRE 16 -1 (-5525 3400)(-5025 3400);
WIRE 16 -1 (-5525 3450)(-5025 3450);
WIRE 16 -1 (-5025 3500)(-5525 3500);
WIRE 16 -1 (-5525 3600)(-5025 3600);
WIRE 16 -1 (-5025 3650)(-5525 3650);
WIRE 16 -1 (-5025 3700)(-5525 3700);
WIRE 16 -1 (-5025 3750)(-5525 3750);
WIRE 16 -1 (-5025 3800)(-5525 3800);
WIRE 16 -1 (-5025 3850)(-5525 3850);
WIRE 16 -1 (-5025 3900)(-5525 3900);
WIRE 16 -1 (-5025 3950)(-5525 3950);
WIRE 16 -1 (-5025 4000)(-5525 4000);
WIRE 16 -1 (-5025 4050)(-5525 4050);
WIRE 16 -1 (-5025 4100)(-5525 4100);
WIRE 16 -1 (-5025 4200)(-5525 4200);
WIRE 16 -1 (-5025 4300)(-5525 4300);
WIRE 16 -1 (-5025 4350)(-5525 4350);
WIRE 16 -1 (-5025 4400)(-5525 4400);
WIRE 16 -1 (-5025 4450)(-5525 4450);
WIRE 16 -1 (-5025 4500)(-5525 4500);
WIRE 16 -1 (-5025 4550)(-5525 4550);
WIRE 16 -1 (-5025 4600)(-5525 4600);
WIRE 16 -1 (-5025 4650)(-5525 4650);
WIRE 16 -1 (-3325 1400)(-2900 1400);
WIRE 16 -1 (-3325 1450)(-2900 1450);
WIRE 16 -1 (-3325 1500)(-2900 1500);
WIRE 16 -1 (-3325 1900)(-2900 1900);
WIRE 16 -1 (-3325 1950)(-2900 1950);
WIRE 16 -1 (-3325 2000)(-2900 2000);
WIRE 16 -1 (-3325 950)(-2900 950);
WIRE 16 -1 (-3325 1000)(-2900 1000);
WIRE 16 -1 (-3325 1050)(-2900 1050);
WIRE 16 -1 (-3325 1100)(-2900 1100);
WIRE 16 -1 (-3325 1150)(-2900 1150);
WIRE 16 -1 (-3325 1200)(-2900 1200);
WIRE 16 -1 (-3325 1250)(-2900 1250);
WIRE 16 -1 (-3325 1300)(-2900 1300);
WIRE 16 -1 (-3325 1650)(-2900 1650);
WIRE 16 -1 (-3325 1700)(-2900 1700);
WIRE 16 -1 (-3325 1750)(-2900 1750);
WIRE 16 -1 (-3325 1800)(-2900 1800);
WIRE 16 -1 (-3325 800)(-2900 800);
WIRE 16 -1 (-3325 850)(-2900 850);
WIRE 16 -1 (-3325 700)(-2900 700);
WIRE 16 -1 (-3325 750)(-2900 750);
WIRE 16 -1 (-3325 2050)(-2900 2050);
WIRE 16 -1 (-3325 2100)(-2900 2100);
WIRE 16 -1 (-3325 2150)(-2900 2150);
WIRE 16 -1 (-3325 2200)(-2900 2200);
WIRE 16 -1 (-3325 2250)(-2900 2250);
WIRE 16 -1 (-3325 2300)(-2900 2300);
WIRE 16 -1 (-3325 2350)(-2900 2350);
WIRE 16 -1 (-3325 2400)(-2900 2400);
WIRE 16 -1 (-3325 2450)(-2900 2450);
WIRE 16 -1 (-3325 2500)(-2900 2500);
WIRE 16 -1 (-3325 2550)(-2900 2550);
WIRE 16 -1 (-3325 2600)(-2900 2600);
WIRE 16 -1 (-3325 2650)(-2900 2650);
WIRE 16 -1 (-3325 2700)(-2900 2700);
WIRE 16 -1 (-3325 2750)(-2900 2750);
WIRE 16 -1 (-3325 3800)(-2900 3800);
WIRE 16 -1 (-3325 3850)(-2900 3850);
WIRE 16 -1 (-3325 3900)(-2900 3900);
WIRE 16 -1 (-3325 3950)(-2900 3950);
WIRE 16 -1 (-3325 4000)(-2900 4000);
WIRE 16 -1 (-3325 4050)(-2900 4050);
WIRE 16 -1 (-3325 2850)(-2900 2850);
WIRE 16 -1 (-3325 2900)(-2900 2900);
WIRE 16 -1 (-3325 2950)(-2900 2950);
WIRE 16 -1 (-3325 3000)(-2900 3000);
WIRE 16 -1 (-3325 3050)(-2900 3050);
WIRE 16 -1 (-3325 3100)(-2900 3100);
WIRE 16 -1 (-3325 3150)(-2900 3150);
WIRE 16 -1 (-3325 3200)(-2900 3200);
WIRE 16 -1 (-3325 3300)(-2900 3300);
WIRE 16 -1 (-3325 3350)(-2900 3350);
WIRE 16 -1 (-3325 3400)(-2900 3400);
WIRE 16 -1 (-3325 3450)(-2900 3450);
WIRE 16 -1 (-3325 3500)(-2900 3500);
WIRE 16 -1 (-3325 3550)(-2900 3550);
WIRE 16 -1 (-3325 3600)(-2900 3600);
WIRE 16 -1 (-3325 3650)(-2900 3650);
WIRE 16 -1 (-3325 3700)(-2900 3700);
WIRE 16 -1 (-3325 500)(-2025 500);
FORCEPROP 2 LAST SIG_NAME M_J_PAR
J 0
(-2700 510);
DISPLAY 0.617021 (-2700 510);
PAINT ORANGE (-2700 510);
WIRE 16 -1 (-3325 550)(-2025 550);
FORCEPROP 2 LAST SIG_NAME M_J_ALERT_N
J 0
(-2700 560);
DISPLAY 0.617021 (-2700 560);
PAINT ORANGE (-2700 560);
WIRE 16 -1 (-3325 600)(-2025 600);
FORCEPROP 2 LAST SIG_NAME M_J_ACT_N
J 0
(-2700 610);
DISPLAY 0.617021 (-2700 610);
PAINT ORANGE (-2700 610);
WIRE 16 -1 (-3325 4100)(-2900 4100);
WIRE 16 -1 (-3325 4150)(-2900 4150);
WIRE 16 -1 (-3325 4200)(-2900 4200);
WIRE 16 -1 (-3325 4250)(-2900 4250);
WIRE 16 -1 (-3325 4300)(-2900 4300);
WIRE 16 -1 (-3325 4350)(-2900 4350);
WIRE 16 -1 (-3325 4400)(-2900 4400);
WIRE 16 -1 (-3325 4450)(-2900 4450);
WIRE 16 -1 (-3325 4500)(-2900 4500);
WIRE 16 -1 (-3325 4550)(-2900 4550);
WIRE 16 -1 (-3325 4600)(-2900 4600);
WIRE 16 -1 (-3325 4650)(-2900 4650);
FORCENOTE
ROOM=CPU1
(-7925 375) 0;
DISPLAY LEFT (-7925 375);
DISPLAY 1.723404 (-7925 375);
PAINT PURPLE (-7925 375);
FORCENOTE
BOM_COST=PROC_SOCKET
(-7925 250) 0;
DISPLAY LEFT (-7925 250);
DISPLAY 1.723404 (-7925 250);
PAINT PURPLE (-7925 250);
QUIT
